FILE_TYPE = MACRO_DRAWING;
SET COLOR_WIRE YELLOW;
SET COLOR_PROP ORANGE;
SET COLOR_DOT WHITE;
SET COLOR_ARC YELLOW;
SET COLOR_BODY GREEN;
SET COLOR_NOTE PURPLE;
SET PROP_DISPLAY VALUE;
SET PAGE_NUMBER P286;
FORCEADD OFFPAGE..4
R 2
(1350 7225);
FORCEPROP 2 LASTPIN (1400 7225) SIG_NAME FM_PVNN_MAIN_CPU1_EN
J 0
(3865 7235);
DISPLAY 0.617021 (3865 7235);
FORCEPROP 2 LAST $XR0 214 
J 0
(1098 7225);
DISPLAY 0.638298 (1098 7225);
PAINT MONO (1098 7225);
FORCEPROP 2 LAST PATH I1
J 0
(1100 7275);
DISPLAY 1.021277 (1100 7275);
DISPLAY INVISIBLE (1100 7275);
FORCEPROP 1 LAST COMMENT_BODY TRUE
J 2
(1375 7125);
DISPLAY 0.872340 (1375 7125);
PAINT GREEN (1375 7125);
DISPLAY INVISIBLE (1375 7125);
FORCEPROP 1 LAST OFFPAGE TRUE
J 2
(1025 7100);
DISPLAY 0.872340 (1025 7100);
PAINT GREEN (1025 7100);
DISPLAY INVISIBLE (1025 7100);
FORCEPROP 2 LAST CDS_LIB standard
J 0
(1350 7225);
DISPLAY INVISIBLE (1350 7225);
FORCEADD Q_CAP..1
(3625 6100);
FORCEPROP 1 LAST PART_NUMBER CH5104KEB02
J 0
(3675 5950);
DISPLAY 0.617021 (3675 5950);
PAINT BLUE (3675 5950);
DISPLAY INVISIBLE (3675 5950);
FORCEPROP 1 LAST TOLERANCE 10%
J 0
(3675 6050);
DISPLAY 0.617021 (3675 6050);
PAINT SKYBLUE (3675 6050);
FORCEPROP 1 LAST MATERIAL X6S
J 0
(3675 6000);
DISPLAY 0.617021 (3675 6000);
PAINT SKYBLUE (3675 6000);
FORCEPROP 1 LAST VOLTAGE 25V
J 0
(3675 6100);
DISPLAY 0.617021 (3675 6100);
PAINT SKYBLUE (3675 6100);
FORCEPROP 1 LAST VALUE 1UF
J 0
(3675 6150);
DISPLAY 0.617021 (3675 6150);
PAINT SKYBLUE (3675 6150);
FORCEPROP 1 LAST PACK_TYPE C0402
J 0
(3675 5900);
DISPLAY 0.617021 (3675 5900);
PAINT SKYBLUE (3675 5900);
FORCEPROP 1 LAST LOCATION PC2222
J 0
(3675 6200);
DISPLAY 0.617021 (3675 6200);
PAINT AQUA (3675 6200);
FORCEPROP 1 LASTPIN (3625 6200) $PN 1
J 0
(3635 6180);
DISPLAY 0.617021 (3635 6180);
PAINT WHITE (3635 6180);
FORCEPROP 1 LASTPIN (3625 6000) $PN 2
J 0
(3635 5980);
DISPLAY 0.617021 (3635 5980);
PAINT WHITE (3635 5980);
FORCEPROP 1 LAST PATH I10
J 0
(3675 6250);
DISPLAY 0.978723 (3675 6250);
PAINT WHITE (3675 6250);
DISPLAY INVISIBLE (3675 6250);
FORCEPROP 2 LAST CDS_LIB pure_quanta
J 0
(3625 6100);
DISPLAY INVISIBLE (3625 6100);
FORCEPROP 2 LAST SEC_TYPE C0402
J 0
(3675 6300);
DISPLAY 1.021277 (3675 6300);
DISPLAY INVISIBLE (3675 6300);
FORCEPROP 2 LAST SEC 1
J 0
(3675 6300);
DISPLAY 0.680851 (3675 6300);
PAINT MONO (3675 6300);
DISPLAY INVISIBLE (3675 6300);
FORCEADD UNIVERSAL_GND..1
(3200 6350);
FORCEPROP 3 LASTPIN (3200 6400) SIG_NAME GND\g
J 0
(3210 6410);
DISPLAY 0.659574 (3210 6410);
PAINT MONO (3210 6410);
DISPLAY INVISIBLE (3210 6410);
FORCEPROP 1 LAST PATH I11
J 0
(3275 6350);
DISPLAY 0.872340 (3275 6350);
PAINT AQUA (3275 6350);
DISPLAY INVISIBLE (3275 6350);
FORCEPROP 1 LAST HDL_POWER GND
J 1
(3225 6275);
DISPLAY 0.702128 (3225 6275);
PAINT GREEN (3225 6275);
DISPLAY INVISIBLE (3225 6275);
FORCEPROP 2 LAST CDS_LIB logical_power
J 0
(3200 6350);
DISPLAY INVISIBLE (3200 6350);
FORCEADD Q_RES..2
(3200 6650);
FORCEPROP 1 LAST PART_NUMBER CS36042FB04
J 0
(3240 6496);
DISPLAY 0.617021 (3240 6496);
PAINT BLUE (3240 6496);
DISPLAY INVISIBLE (3240 6496);
FORCEPROP 1 LAST VALUE 60.4K
J 0
(3245 6696);
DISPLAY 0.617021 (3245 6696);
PAINT SKYBLUE (3245 6696);
FORCEPROP 1 LAST WATTAGE 1/16W
J 0
(3240 6596);
DISPLAY 0.617021 (3240 6596);
PAINT SKYBLUE (3240 6596);
FORCEPROP 1 LAST MATERIAL CHIP
J 0
(3240 6546);
DISPLAY 0.617021 (3240 6546);
PAINT SKYBLUE (3240 6546);
FORCEPROP 1 LAST PACK_TYPE 0402LF
J 0
(3240 6446);
DISPLAY 0.617021 (3240 6446);
PAINT SKYBLUE (3240 6446);
FORCEPROP 1 LAST TOLERANCE 1%
J 0
(3245 6646);
DISPLAY 0.617021 (3245 6646);
PAINT SKYBLUE (3245 6646);
FORCEPROP 1 LAST LOCATION PR2220
J 0
(3250 6746);
DISPLAY 0.617021 (3250 6746);
PAINT AQUA (3250 6746);
FORCEPROP 1 LAST PATH I12
J 0
(3250 6825);
DISPLAY 0.978723 (3250 6825);
PAINT WHITE (3250 6825);
DISPLAY INVISIBLE (3250 6825);
FORCEPROP 2 LAST CDS_LIB pure_quanta
J 0
(3200 6603);
DISPLAY INVISIBLE (3200 6603);
FORCEPROP 0 LAST $SEC 1
J 0
(3250 6775);
DISPLAY 0.680851 (3250 6775);
PAINT MONO (3250 6775);
DISPLAY INVISIBLE (3250 6775);
FORCEPROP 0 LAST CDS_SEC 1
J 0
(3250 6775);
DISPLAY 1.021277 (3250 6775);
DISPLAY INVISIBLE (3250 6775);
FORCEPROP 1 LASTPIN (3200 6750) $PN 1
J 0
(3205 6674);
DISPLAY 0.808511 (3205 6674);
PAINT WHITE (3205 6674);
DISPLAY INVISIBLE (3205 6674);
FORCEPROP 1 LASTPIN (3200 6550) $PN 2
J 0
(3205 6522);
DISPLAY 0.808511 (3205 6522);
PAINT WHITE (3205 6522);
DISPLAY INVISIBLE (3205 6522);
FORCEADD Q_RES..2
(3625 6725);
FORCEPROP 1 LAST PART_NUMBER CS00002JB13
J 0
(3665 6600);
DISPLAY 0.617021 (3665 6600);
PAINT BLUE (3665 6600);
DISPLAY INVISIBLE (3665 6600);
FORCEPROP 1 LAST TOLERANCE 5%
J 0
(3670 6750);
DISPLAY 0.617021 (3670 6750);
PAINT SKYBLUE (3670 6750);
FORCEPROP 1 LAST MATERIAL CHIP
J 0
(3665 6650);
DISPLAY 0.617021 (3665 6650);
PAINT SKYBLUE (3665 6650);
FORCEPROP 1 LAST VALUE 0
J 0
(3670 6800);
DISPLAY 0.617021 (3670 6800);
PAINT SKYBLUE (3670 6800);
FORCEPROP 1 LAST WATTAGE 1/16W
J 0
(3665 6700);
DISPLAY 0.617021 (3665 6700);
PAINT SKYBLUE (3665 6700);
FORCEPROP 1 LAST PACK_TYPE 0402LF
J 0
(3665 6550);
DISPLAY 0.617021 (3665 6550);
PAINT SKYBLUE (3665 6550);
FORCEPROP 1 LAST LOCATION PR3338
J 0
(3670 6850);
DISPLAY 0.617021 (3670 6850);
PAINT AQUA (3670 6850);
FORCEPROP 1 LASTPIN (3625 6825) $PN 1
J 0
(3630 6787);
DISPLAY 0.787234 (3630 6787);
PAINT MONO (3630 6787);
FORCEPROP 1 LASTPIN (3625 6625) $PN 2
J 0
(3630 6635);
DISPLAY 0.787234 (3630 6635);
PAINT MONO (3630 6635);
FORCEPROP 1 LAST PATH I13
J 0
(3675 6900);
DISPLAY 0.978723 (3675 6900);
PAINT WHITE (3675 6900);
DISPLAY INVISIBLE (3675 6900);
FORCEPROP 2 LAST CDS_LIB pure_quanta
J 0
(3625 6725);
DISPLAY INVISIBLE (3625 6725);
FORCEPROP 0 LAST $SEC 1
J 0
(3675 6900);
DISPLAY 0.680851 (3675 6900);
PAINT MONO (3675 6900);
DISPLAY INVISIBLE (3675 6900);
FORCEPROP 0 LAST CDS_SEC 1
J 0
(3675 6900);
DISPLAY 1.021277 (3675 6900);
DISPLAY INVISIBLE (3675 6900);
FORCEADD Q_CAP..1
(2900 7950);
FORCEPROP 1 LAST PART_NUMBER CH6223MEA01
J 0
(2950 7750);
DISPLAY 0.617021 (2950 7750);
PAINT BLUE (2950 7750);
DISPLAY INVISIBLE (2950 7750);
FORCEPROP 1 LAST MATERIAL X6S
J 0
(2950 7850);
DISPLAY 0.617021 (2950 7850);
PAINT SKYBLUE (2950 7850);
FORCEPROP 1 LAST TOLERANCE 20%
J 0
(2950 7900);
DISPLAY 0.617021 (2950 7900);
PAINT SKYBLUE (2950 7900);
FORCEPROP 1 LAST VOLTAGE 16V
J 0
(2950 7950);
DISPLAY 0.617021 (2950 7950);
PAINT SKYBLUE (2950 7950);
FORCEPROP 1 LAST PACK_TYPE C0805
J 0
(2950 7800);
DISPLAY 0.617021 (2950 7800);
PAINT SKYBLUE (2950 7800);
FORCEPROP 1 LAST VALUE 22UF
J 0
(2950 8000);
DISPLAY 0.617021 (2950 8000);
PAINT SKYBLUE (2950 8000);
FORCEPROP 1 LAST LOCATION PC1281
J 0
(2950 8050);
DISPLAY 0.617021 (2950 8050);
PAINT AQUA (2950 8050);
FORCEPROP 1 LASTPIN (2900 8050) $PN 1
J 0
(2910 8030);
DISPLAY 0.617021 (2910 8030);
PAINT MONO (2910 8030);
FORCEPROP 1 LASTPIN (2900 7850) $PN 2
J 0
(2910 7830);
DISPLAY 0.617021 (2910 7830);
PAINT MONO (2910 7830);
FORCEPROP 1 LAST PATH I14
J 0
(2950 8100);
DISPLAY 0.978723 (2950 8100);
PAINT WHITE (2950 8100);
DISPLAY INVISIBLE (2950 8100);
FORCEPROP 2 LAST CDS_LIB pure_quanta
J 0
(2900 7950);
DISPLAY INVISIBLE (2900 7950);
FORCEPROP 2 LAST BOM_COST VR_PCH
J 0
(2950 8100);
DISPLAY 0.680851 (2950 8100);
DISPLAY INVISIBLE (2950 8100);
FORCEPROP 2 LAST $SEC 1
J 0
(2950 8150);
DISPLAY 0.680851 (2950 8150);
PAINT MONO (2950 8150);
DISPLAY INVISIBLE (2950 8150);
FORCEPROP 2 LAST CDS_SEC 1
J 0
(2950 8150);
DISPLAY 1.021277 (2950 8150);
DISPLAY INVISIBLE (2950 8150);
FORCEADD UNIVERSAL_POWER..1
(3625 6900);
FORCEPROP 3 LASTPIN (3625 6850) SIG_NAME P3V3_AUX\g
J 0
(3635 6860);
DISPLAY 0.659574 (3635 6860);
PAINT MONO (3635 6860);
DISPLAY INVISIBLE (3635 6860);
FORCEPROP 1 LAST HDL_POWER P3V3_AUX
J 1
(3625 6950);
DISPLAY 0.617021 (3625 6950);
PAINT GREEN (3625 6950);
FORCEPROP 1 LAST PATH I15
J 0
(3675 6925);
DISPLAY 0.872340 (3675 6925);
PAINT AQUA (3675 6925);
DISPLAY INVISIBLE (3675 6925);
FORCEPROP 2 LAST CDS_LIB logical_power
J 0
(3625 6900);
DISPLAY INVISIBLE (3625 6900);
FORCEADD Q_CAP..1
(3325 7950);
FORCEPROP 1 LAST PART_NUMBER CH5103KEB01
J 0
(3375 7750);
DISPLAY 0.617021 (3375 7750);
PAINT BLUE (3375 7750);
DISPLAY INVISIBLE (3375 7750);
FORCEPROP 1 LAST PACK_TYPE C0402
J 0
(3375 7800);
DISPLAY 0.617021 (3375 7800);
PAINT SKYBLUE (3375 7800);
FORCEPROP 1 LAST TOLERANCE 10%
J 0
(3375 7900);
DISPLAY 0.617021 (3375 7900);
PAINT SKYBLUE (3375 7900);
FORCEPROP 1 LAST VOLTAGE 16V
J 0
(3375 7950);
DISPLAY 0.617021 (3375 7950);
PAINT SKYBLUE (3375 7950);
FORCEPROP 1 LAST MATERIAL X6S
J 0
(3375 7850);
DISPLAY 0.617021 (3375 7850);
PAINT SKYBLUE (3375 7850);
FORCEPROP 1 LAST VALUE 1UF
J 0
(3375 8000);
DISPLAY 0.617021 (3375 8000);
PAINT SKYBLUE (3375 8000);
FORCEPROP 1 LAST LOCATION PC1282
J 0
(3375 8050);
DISPLAY 0.617021 (3375 8050);
PAINT AQUA (3375 8050);
FORCEPROP 1 LASTPIN (3325 8050) $PN 1
J 0
(3335 8030);
DISPLAY 0.617021 (3335 8030);
FORCEPROP 1 LASTPIN (3325 7850) $PN 2
J 0
(3335 7830);
DISPLAY 0.617021 (3335 7830);
FORCEPROP 1 LAST PATH I16
J 0
(3375 8100);
DISPLAY 0.978723 (3375 8100);
PAINT WHITE (3375 8100);
DISPLAY INVISIBLE (3375 8100);
FORCEPROP 2 LAST CDS_LIB pure_quanta
J 0
(3325 7950);
PAINT MONO (3325 7950);
DISPLAY INVISIBLE (3325 7950);
FORCEPROP 1 LAST LOCATION PC1282
J 0
(3375 8125);
DISPLAY 1.021277 (3375 8125);
PAINT AQUA (3375 8125);
DISPLAY INVISIBLE (3375 8125);
FORCEPROP 2 LAST $SEC 1
J 0
(3375 8150);
DISPLAY 0.680851 (3375 8150);
PAINT MONO (3375 8150);
DISPLAY INVISIBLE (3375 8150);
FORCEPROP 2 LAST CDS_SEC 1
J 0
(3375 8150);
DISPLAY 1.021277 (3375 8150);
DISPLAY INVISIBLE (3375 8150);
FORCEADD UNIVERSAL_GND..1
(4075 5725);
FORCEPROP 3 LASTPIN (4075 5775) SIG_NAME GND\g
J 0
(4085 5785);
DISPLAY 0.659574 (4085 5785);
PAINT MONO (4085 5785);
DISPLAY INVISIBLE (4085 5785);
FORCEPROP 1 LAST PATH I17
J 0
(4150 5725);
DISPLAY 0.872340 (4150 5725);
PAINT AQUA (4150 5725);
DISPLAY INVISIBLE (4150 5725);
FORCEPROP 1 LAST HDL_POWER GND
J 1
(4100 5650);
DISPLAY 0.702128 (4100 5650);
PAINT GREEN (4100 5650);
DISPLAY INVISIBLE (4100 5650);
FORCEPROP 2 LAST CDS_LIB logical_power
J 0
(4075 5725);
DISPLAY INVISIBLE (4075 5725);
FORCEADD UNIVERSAL_GND..1
(5400 5625);
FORCEPROP 3 LASTPIN (5400 5675) SIG_NAME GND\g
J 0
(5410 5685);
DISPLAY 0.659574 (5410 5685);
PAINT MONO (5410 5685);
DISPLAY INVISIBLE (5410 5685);
FORCEPROP 1 LAST PATH I18
J 0
(5475 5625);
DISPLAY 0.872340 (5475 5625);
PAINT AQUA (5475 5625);
DISPLAY INVISIBLE (5475 5625);
FORCEPROP 1 LAST HDL_POWER GND
J 1
(5425 5550);
DISPLAY 0.702128 (5425 5550);
PAINT GREEN (5425 5550);
DISPLAY INVISIBLE (5425 5550);
FORCEPROP 2 LAST CDS_LIB logical_power
J 0
(5400 5625);
DISPLAY INVISIBLE (5400 5625);
FORCEADD Q_RES..2
(4075 6050);
FORCEPROP 1 LAST PART_NUMBER CS33482FB04
J 0
(4115 5925);
DISPLAY 0.617021 (4115 5925);
PAINT BLUE (4115 5925);
DISPLAY INVISIBLE (4115 5925);
FORCEPROP 1 LAST TOLERANCE 1%
J 0
(4120 6075);
DISPLAY 0.617021 (4120 6075);
PAINT SKYBLUE (4120 6075);
FORCEPROP 1 LAST VALUE 34.8K
J 0
(4120 6125);
DISPLAY 0.617021 (4120 6125);
PAINT SKYBLUE (4120 6125);
FORCEPROP 1 LAST WATTAGE 1/16W
J 0
(4115 6025);
DISPLAY 0.617021 (4115 6025);
PAINT SKYBLUE (4115 6025);
FORCEPROP 1 LAST PACK_TYPE 0402LF
J 0
(4115 5875);
DISPLAY 0.617021 (4115 5875);
PAINT SKYBLUE (4115 5875);
FORCEPROP 1 LAST MATERIAL CHIP
J 0
(4115 5975);
DISPLAY 0.617021 (4115 5975);
PAINT SKYBLUE (4115 5975);
FORCEPROP 1 LAST LOCATION PR2222
J 0
(4120 6175);
DISPLAY 0.617021 (4120 6175);
PAINT AQUA (4120 6175);
FORCEPROP 1 LASTPIN (4075 6150) $PN 1
J 0
(4080 6112);
DISPLAY 0.617021 (4080 6112);
PAINT MONO (4080 6112);
FORCEPROP 1 LASTPIN (4075 5950) $PN 2
J 0
(4080 5960);
DISPLAY 0.617021 (4080 5960);
PAINT MONO (4080 5960);
FORCEPROP 1 LAST PATH I19
J 0
(4125 6225);
DISPLAY 0.978723 (4125 6225);
PAINT WHITE (4125 6225);
DISPLAY INVISIBLE (4125 6225);
FORCEPROP 2 LAST CDS_LIB pure_quanta
J 0
(4075 6050);
DISPLAY INVISIBLE (4075 6050);
FORCEPROP 0 LAST $SEC 1
J 0
(4125 6225);
DISPLAY 0.680851 (4125 6225);
PAINT MONO (4125 6225);
DISPLAY INVISIBLE (4125 6225);
FORCEPROP 0 LAST CDS_SEC 1
J 0
(4125 6225);
DISPLAY 1.021277 (4125 6225);
DISPLAY INVISIBLE (4125 6225);
FORCEADD VCCAUX15..1
(1200 7500);
FORCEPROP 3 LASTPIN (1200 7450) SIG_NAME P3V3_AUX\g
J 0
(1210 7460);
DISPLAY 0.659574 (1210 7460);
PAINT MONO (1210 7460);
DISPLAY INVISIBLE (1210 7460);
FORCEPROP 1 LAST HDL_POWER P3V3_AUX
J 1
(1200 7542);
DISPLAY 0.617021 (1200 7542);
PAINT GREEN (1200 7542);
FORCEPROP 1 LAST PATH I2
J 0
(1250 7525);
DISPLAY 0.872340 (1250 7525);
PAINT AQUA (1250 7525);
DISPLAY INVISIBLE (1250 7525);
FORCEPROP 2 LAST CDS_LIB logical_power
J 0
(1200 7500);
PAINT MONO (1200 7500);
DISPLAY INVISIBLE (1200 7500);
FORCEPROP 2 LAST BOM_COST VR_PCH
J 0
(1200 7575);
DISPLAY 0.680851 (1200 7575);
DISPLAY INVISIBLE (1200 7575);
FORCEADD RS53317LR..1
(4950 7050);
FORCEPROP 1 LAST PART_NUMBER AL053317005
J 0
(4703 7906);
DISPLAY 0.723404 (4703 7906);
PAINT GREEN (4703 7906);
DISPLAY INVISIBLE (4703 7906);
FORCEPROP 2 LAST VALUE RS53317LR
J 0
(4700 7950);
DISPLAY 0.617021 (4700 7950);
PAINT SKYBLUE (4700 7950);
FORCEPROP 2 LAST PART_TYPE SMLF
J 0
(4700 8000);
DISPLAY 0.638298 (4700 8000);
PAINT SKYBLUE (4700 8000);
FORCEPROP 1 LAST MATERIAL IC
J 0
(4703 7779);
DISPLAY 0.723404 (4703 7779);
PAINT GREEN (4703 7779);
FORCEPROP 1 LAST LOCATION PU82
J 0
(4703 8053);
DISPLAY 0.723404 (4703 8053);
PAINT GREEN (4703 8053);
FORCEPROP 2 LASTPIN (5350 6375) $PN 7
J 0
(5360 6385);
DISPLAY 0.680851 (5360 6385);
PAINT MONO (5360 6385);
FORCEPROP 2 LASTPIN (5350 7525) $PN 10
J 0
(5360 7535);
DISPLAY 0.680851 (5360 7535);
PAINT MONO (5360 7535);
FORCEPROP 2 LASTPIN (4550 6425) $PN 4
J 2
(4540 6435);
DISPLAY 0.680851 (4540 6435);
PAINT MONO (4540 6435);
FORCEPROP 2 LASTPIN (4550 7225) $PN 5
J 2
(4540 7235);
DISPLAY 0.680851 (4540 7235);
PAINT MONO (4540 7235);
FORCEPROP 2 LASTPIN (5350 6775) $PN 6
J 0
(5360 6785);
DISPLAY 0.680851 (5360 6785);
PAINT MONO (5360 6785);
FORCEPROP 2 LASTPIN (4550 7025) $PN 12
J 2
(4540 7035);
DISPLAY 0.680851 (4540 7035);
PAINT MONO (4540 7035);
FORCEPROP 2 LASTPIN (5350 6625) $PN 1
J 0
(5360 6635);
DISPLAY 0.680851 (5360 6635);
PAINT MONO (5360 6635);
FORCEPROP 2 LASTPIN (5350 6425) $PN 14
J 0
(5360 6435);
DISPLAY 0.680851 (5360 6435);
PAINT MONO (5360 6435);
FORCEPROP 2 LASTPIN (5350 7725) $PN 9
J 0
(5360 7735);
DISPLAY 0.680851 (5360 7735);
PAINT MONO (5360 7735);
FORCEPROP 2 LASTPIN (5350 6525) $PN 8
J 0
(5360 6535);
DISPLAY 0.680851 (5360 6535);
PAINT MONO (5360 6535);
FORCEPROP 2 LASTPIN (5350 7275) $PN 2
J 0
(5360 7285);
DISPLAY 0.680851 (5360 7285);
PAINT MONO (5360 7285);
FORCEPROP 2 LASTPIN (5350 7225) $PN 11
J 0
(5360 7235);
DISPLAY 0.680851 (5360 7235);
PAINT MONO (5360 7235);
FORCEPROP 2 LASTPIN (4550 6775) $PN 13
J 2
(4540 6785);
DISPLAY 0.680851 (4540 6785);
PAINT MONO (4540 6785);
FORCEPROP 2 LASTPIN (4550 7725) $PN 3
J 2
(4540 7735);
DISPLAY 0.680851 (4540 7735);
PAINT MONO (4540 7735);
FORCEPROP 1 LAST PATH I20
J 0
(4950 7050);
DISPLAY 0.723404 (4950 7050);
PAINT GREEN (4950 7050);
DISPLAY INVISIBLE (4950 7050);
FORCEPROP 1 LAST CDS_LMAN_SYM_OUTLINE -250,725,250,-725
J 0
(4950 7050);
DISPLAY 0.468085 (4950 7050);
PAINT GREEN (4950 7050);
DISPLAY INVISIBLE (4950 7050);
FORCEPROP 1 LAST NEEDS_NO_SIZE TRUE
J 0
(4950 7050);
DISPLAY 0.723404 (4950 7050);
PAINT GREEN (4950 7050);
DISPLAY INVISIBLE (4950 7050);
FORCEPROP 2 LAST CDS_LIB pure_quanta
J 0
(4950 7050);
DISPLAY INVISIBLE (4950 7050);
FORCEPROP 2 LAST SEC_TYPE 
J 0
(4750 8200);
DISPLAY 1.021277 (4750 8200);
DISPLAY INVISIBLE (4750 8200);
FORCEPROP 2 LAST SEC 1
J 0
(4750 8200);
DISPLAY 0.680851 (4750 8200);
PAINT MONO (4750 8200);
DISPLAY INVISIBLE (4750 8200);
FORCEADD UNIVERSAL_GND..1
(5550 6125);
FORCEPROP 3 LASTPIN (5550 6175) SIG_NAME GND\g
J 0
(5560 6185);
DISPLAY 0.659574 (5560 6185);
PAINT MONO (5560 6185);
DISPLAY INVISIBLE (5560 6185);
FORCEPROP 1 LAST PATH I21
J 0
(5625 6125);
DISPLAY 0.872340 (5625 6125);
PAINT AQUA (5625 6125);
DISPLAY INVISIBLE (5625 6125);
FORCEPROP 1 LAST HDL_POWER GND
J 1
(5575 6050);
DISPLAY 0.702128 (5575 6050);
PAINT GREEN (5575 6050);
DISPLAY INVISIBLE (5575 6050);
FORCEPROP 2 LAST CDS_LIB logical_power
J 0
(5550 6125);
DISPLAY INVISIBLE (5550 6125);
FORCEADD Q_RES..1
(6475 5750);
FORCEPROP 1 LAST PART_NUMBER CS00002JB13
J 0
(6300 5675);
DISPLAY 0.638298 (6300 5675);
DISPLAY INVISIBLE (6300 5675);
FORCEPROP 1 LAST WATTAGE 1/16W
J 2
(6450 5625);
DISPLAY 0.638298 (6450 5625);
FORCEPROP 1 LAST MATERIAL CHIP
J 0
(6875 5750);
DISPLAY 0.638298 (6875 5750);
FORCEPROP 1 LAST TOLERANCE 5%
J 0
(6775 5750);
DISPLAY 0.638298 (6775 5750);
FORCEPROP 1 LAST VALUE 0
J 2
(6725 5750);
DISPLAY 0.638298 (6725 5750);
FORCEPROP 1 LAST PACK_TYPE 0402LF
J 0
(6500 5625);
DISPLAY 0.638298 (6500 5625);
FORCEPROP 1 LAST LOCATION PR2
J 0
(6225 5750);
DISPLAY 0.978723 (6225 5750);
FORCEPROP 1 LASTPIN (6375 5750) $PN 1
J 0
(6387 5762);
DISPLAY 0.787234 (6387 5762);
PAINT MONO (6387 5762);
FORCEPROP 1 LASTPIN (6575 5750) $PN 2
J 0
(6537 5762);
DISPLAY 0.787234 (6537 5762);
PAINT MONO (6537 5762);
FORCEPROP 2 LAST CDS_LIB pure_quanta
J 0
(6475 5750);
DISPLAY INVISIBLE (6475 5750);
FORCEPROP 1 LAST PATH I22
J 0
(6425 5900);
DISPLAY 0.978723 (6425 5900);
PAINT WHITE (6425 5900);
DISPLAY INVISIBLE (6425 5900);
FORCEPROP 0 LAST $SEC 1
J 0
(6875 5800);
DISPLAY 0.680851 (6875 5800);
PAINT MONO (6875 5800);
DISPLAY INVISIBLE (6875 5800);
FORCEPROP 0 LAST CDS_SEC 1
J 0
(6875 5800);
DISPLAY 1.021277 (6875 5800);
DISPLAY INVISIBLE (6875 5800);
FORCEADD Q_CAP..1
(6025 6050);
FORCEPROP 1 LAST PART_NUMBER TMP_QCH2336K1B12
J 0
(6100 5950);
DISPLAY 0.617021 (6100 5950);
PAINT BLUE (6100 5950);
DISPLAY INVISIBLE (6100 5950);
FORCEPROP 1 LAST TOLERANCE 10%
J 0
(6100 6050);
DISPLAY 0.617021 (6100 6050);
PAINT SKYBLUE (6100 6050);
FORCEPROP 1 LAST MATERIAL X7R
J 0
(6100 6000);
DISPLAY 0.617021 (6100 6000);
PAINT SKYBLUE (6100 6000);
FORCEPROP 1 LAST PACK_TYPE 0402
J 0
(6100 5900);
DISPLAY 0.617021 (6100 5900);
PAINT SKYBLUE (6100 5900);
FORCEPROP 1 LAST VOLTAGE 50V
J 0
(6100 6100);
DISPLAY 0.617021 (6100 6100);
PAINT SKYBLUE (6100 6100);
FORCEPROP 1 LAST VALUE 3300PF
J 0
(6100 6150);
DISPLAY 0.617021 (6100 6150);
PAINT SKYBLUE (6100 6150);
FORCEPROP 1 LAST LOCATION PC28
J 0
(6100 6200);
DISPLAY 0.617021 (6100 6200);
PAINT AQUA (6100 6200);
FORCEPROP 1 LAST PATH I23
J 0
(6075 6200);
DISPLAY 0.978723 (6075 6200);
PAINT WHITE (6075 6200);
DISPLAY INVISIBLE (6075 6200);
FORCEPROP 2 LAST CDS_LIB pure_quanta
J 0
(6025 6050);
DISPLAY INVISIBLE (6025 6050);
FORCEPROP 0 LAST $SEC 1
J 0
(6075 6200);
DISPLAY 0.680851 (6075 6200);
PAINT MONO (6075 6200);
DISPLAY INVISIBLE (6075 6200);
FORCEPROP 0 LAST CDS_SEC 1
J 0
(6075 6200);
DISPLAY 1.021277 (6075 6200);
DISPLAY INVISIBLE (6075 6200);
FORCEPROP 1 LASTPIN (6025 6150) $PN 1
J 0
(6035 6130);
DISPLAY 0.808511 (6035 6130);
PAINT WHITE (6035 6130);
DISPLAY INVISIBLE (6035 6130);
FORCEPROP 1 LASTPIN (6025 5950) $PN 2
J 0
(6035 5930);
DISPLAY 0.808511 (6035 5930);
PAINT WHITE (6035 5930);
DISPLAY INVISIBLE (6035 5930);
FORCEADD Q_CAP..1
(6700 7375);
FORCEPROP 1 LAST PART_NUMBER CH4224K1B01
J 0
(6750 7325);
DISPLAY 0.489362 (6750 7325);
PAINT BLUE (6750 7325);
DISPLAY INVISIBLE (6750 7325);
FORCEPROP 1 LAST VOLTAGE 25V
J 0
(6750 7400);
DISPLAY 0.489362 (6750 7400);
PAINT SKYBLUE (6750 7400);
FORCEPROP 1 LAST TOLERANCE 10%
J 0
(6750 7375);
DISPLAY 0.489362 (6750 7375);
PAINT SKYBLUE (6750 7375);
FORCEPROP 1 LAST VALUE 0.22UF
J 0
(6750 7425);
DISPLAY 0.489362 (6750 7425);
PAINT SKYBLUE (6750 7425);
FORCEPROP 1 LAST MATERIAL X7R
J 0
(6750 7350);
DISPLAY 0.489362 (6750 7350);
PAINT SKYBLUE (6750 7350);
FORCEPROP 1 LAST PACK_TYPE C0402
J 0
(6750 7300);
DISPLAY 0.489362 (6750 7300);
PAINT SKYBLUE (6750 7300);
FORCEPROP 1 LAST LOCATION PC1283
J 0
(6750 7450);
DISPLAY 0.489362 (6750 7450);
PAINT AQUA (6750 7450);
FORCEPROP 1 LASTPIN (6700 7475) $PN 1
J 0
(6710 7455);
DISPLAY 0.617021 (6710 7455);
PAINT MONO (6710 7455);
FORCEPROP 1 LASTPIN (6700 7275) $PN 2
J 0
(6710 7255);
DISPLAY 0.617021 (6710 7255);
PAINT MONO (6710 7255);
FORCEPROP 1 LAST PATH I24
J 0
(6750 7525);
DISPLAY 0.978723 (6750 7525);
PAINT WHITE (6750 7525);
DISPLAY INVISIBLE (6750 7525);
FORCEPROP 2 LAST CDS_LIB pure_quanta
J 0
(6700 7375);
DISPLAY INVISIBLE (6700 7375);
FORCEPROP 2 LAST $SEC 1
J 0
(6750 7575);
DISPLAY 0.680851 (6750 7575);
PAINT MONO (6750 7575);
DISPLAY INVISIBLE (6750 7575);
FORCEPROP 2 LAST CDS_SEC 1
J 0
(6750 7575);
DISPLAY 1.021277 (6750 7575);
DISPLAY INVISIBLE (6750 7575);
FORCEADD Q_RES..1
(6375 7525);
FORCEPROP 1 LAST PART_NUMBER CS00002JB13
J 0
(6225 7450);
DISPLAY 0.617021 (6225 7450);
PAINT BLUE (6225 7450);
DISPLAY INVISIBLE (6225 7450);
FORCEPROP 1 LAST MATERIAL CHIP
J 0
(6225 7400);
DISPLAY 0.617021 (6225 7400);
PAINT SKYBLUE (6225 7400);
FORCEPROP 1 LAST PACK_TYPE 0402LF
J 0
(6400 7400);
DISPLAY 0.638298 (6400 7400);
PAINT SKYBLUE (6400 7400);
FORCEPROP 1 LAST TOLERANCE 5%
J 0
(6425 7600);
DISPLAY 0.617021 (6425 7600);
PAINT SKYBLUE (6425 7600);
FORCEPROP 1 LAST VALUE 0
J 2
(6375 7600);
DISPLAY 0.617021 (6375 7600);
PAINT SKYBLUE (6375 7600);
FORCEPROP 1 LAST LOCATION PR4272
J 0
(6175 7525);
DISPLAY 0.574468 (6175 7525);
PAINT AQUA (6175 7525);
FORCEPROP 1 LASTPIN (6275 7525) $PN 1
J 0
(6287 7537);
DISPLAY 0.787234 (6287 7537);
PAINT MONO (6287 7537);
FORCEPROP 1 LASTPIN (6475 7525) $PN 2
J 0
(6437 7537);
DISPLAY 0.787234 (6437 7537);
PAINT MONO (6437 7537);
FORCEPROP 1 LAST PATH I25
J 0
(6325 7675);
DISPLAY 0.978723 (6325 7675);
PAINT WHITE (6325 7675);
DISPLAY INVISIBLE (6325 7675);
FORCEPROP 1 LAST WATTAGE 1/16W
J 2
(6550 7600);
DISPLAY 0.404255 (6550 7600);
PAINT SKYBLUE (6550 7600);
DISPLAY INVISIBLE (6550 7600);
FORCEPROP 2 LAST SEC_TYPE 0402LF
J 0
(6325 7725);
DISPLAY 1.021277 (6325 7725);
DISPLAY INVISIBLE (6325 7725);
FORCEPROP 2 LAST CDS_LIB pure_quanta
J 0
(6375 7525);
DISPLAY INVISIBLE (6375 7525);
FORCEPROP 2 LAST SEC 1
J 0
(6325 7725);
DISPLAY 0.680851 (6325 7725);
PAINT MONO (6325 7725);
DISPLAY INVISIBLE (6325 7725);
FORCEADD Q_RES..2
(7075 6050);
FORCEPROP 1 LAST PART_NUMBER CS31242BB10
J 0
(7115 5896);
DISPLAY 0.617021 (7115 5896);
PAINT BLUE (7115 5896);
DISPLAY INVISIBLE (7115 5896);
FORCEPROP 1 LAST WATTAGE 1/16W
J 0
(7115 5996);
DISPLAY 0.617021 (7115 5996);
PAINT SKYBLUE (7115 5996);
FORCEPROP 1 LAST TOLERANCE 0.1%
J 0
(7120 6046);
DISPLAY 0.617021 (7120 6046);
PAINT SKYBLUE (7120 6046);
FORCEPROP 1 LAST VALUE 12.4K
J 0
(7120 6096);
DISPLAY 0.617021 (7120 6096);
PAINT SKYBLUE (7120 6096);
FORCEPROP 1 LAST PACK_TYPE 0402LF
J 0
(7115 5846);
DISPLAY 0.617021 (7115 5846);
PAINT SKYBLUE (7115 5846);
FORCEPROP 1 LAST MATERIAL CHIP
J 0
(7115 5946);
DISPLAY 0.617021 (7115 5946);
PAINT SKYBLUE (7115 5946);
FORCEPROP 1 LAST LOCATION PR51
J 0
(7125 6150);
DISPLAY 0.765957 (7125 6150);
PAINT AQUA (7125 6150);
FORCEPROP 1 LASTPIN (7075 6150) $PN 1
J 0
(7090 6135);
DISPLAY 0.617021 (7090 6135);
PAINT WHITE (7090 6135);
FORCEPROP 1 LASTPIN (7075 5950) $PN 2
J 0
(7090 5935);
DISPLAY 0.617021 (7090 5935);
PAINT WHITE (7090 5935);
FORCEPROP 1 LAST PATH I26
J 0
(7125 6225);
DISPLAY 0.978723 (7125 6225);
PAINT WHITE (7125 6225);
DISPLAY INVISIBLE (7125 6225);
FORCEPROP 2 LAST SEC_TYPE 0402LF
J 0
(7100 5727);
DISPLAY 1.021277 (7100 5727);
DISPLAY INVISIBLE (7100 5727);
FORCEPROP 2 LAST CDS_LIB pure_quanta
J 0
(7075 6003);
DISPLAY INVISIBLE (7075 6003);
FORCEPROP 0 LAST SEC 1
J 0
(7125 5818);
DISPLAY 0.680851 (7125 5818);
PAINT MONO (7125 5818);
DISPLAY INVISIBLE (7125 5818);
FORCEADD Q_INDUCTOR..1
(7300 7250);
FORCEPROP 1 LAST PART_NUMBER CV-4755MZ12
J 0
(7175 7360);
DISPLAY 0.617021 (7175 7360);
PAINT BLUE (7175 7360);
DISPLAY INVISIBLE (7175 7360);
FORCEPROP 2 LAST VALUE 4.7UH
J 0
(7175 7425);
DISPLAY 0.617021 (7175 7425);
PAINT SKYBLUE (7175 7425);
FORCEPROP 1 LAST MATERIAL IND
J 0
(7175 7305);
DISPLAY 0.617021 (7175 7305);
PAINT SKYBLUE (7175 7305);
FORCEPROP 2 LAST PACK_TYPE SMLF
J 0
(7175 7475);
DISPLAY 0.617021 (7175 7475);
PAINT SKYBLUE (7175 7475);
FORCEPROP 1 LAST LOCATION PL121
J 0
(7050 7235);
DISPLAY 0.617021 (7050 7235);
PAINT AQUA (7050 7235);
FORCEPROP 2 LASTPIN (7200 7225) $PN 1
J 2
(7190 7235);
DISPLAY 0.617021 (7190 7235);
FORCEPROP 2 LASTPIN (7400 7225) $PN 2
J 0
(7410 7235);
DISPLAY 0.617021 (7410 7235);
FORCEPROP 1 LAST PATH I27
J 0
(7375 7305);
DISPLAY 0.723404 (7375 7305);
PAINT GREEN (7375 7305);
DISPLAY INVISIBLE (7375 7305);
FORCEPROP 2 LAST BOM_COST VR_PCH
J 0
(7175 7550);
DISPLAY 0.680851 (7175 7550);
DISPLAY INVISIBLE (7175 7550);
FORCEPROP 2 LAST CDS_LIB pure_quanta
J 0
(7300 7250);
PAINT MONO (7300 7250);
DISPLAY INVISIBLE (7300 7250);
FORCEPROP 1 LAST NEEDS_NO_SIZE TRUE
J 0
(7300 7250);
DISPLAY 0.468085 (7300 7250);
PAINT GREEN (7300 7250);
DISPLAY INVISIBLE (7300 7250);
FORCEPROP 2 LAST $SEC 1
J 0
(7175 7525);
DISPLAY 0.680851 (7175 7525);
PAINT MONO (7175 7525);
DISPLAY INVISIBLE (7175 7525);
FORCEPROP 2 LAST CDS_SEC 1
J 0
(7175 7525);
DISPLAY 1.021277 (7175 7525);
DISPLAY INVISIBLE (7175 7525);
FORCEADD Q_CAP..1
(7725 7025);
FORCEPROP 1 LAST PART_NUMBER CH4106K1B01
J 0
(7775 6825);
DISPLAY 0.617021 (7775 6825);
PAINT BLUE (7775 6825);
DISPLAY INVISIBLE (7775 6825);
FORCEPROP 1 LAST VOLTAGE 50V
J 0
(7775 7025);
DISPLAY 0.617021 (7775 7025);
PAINT SKYBLUE (7775 7025);
FORCEPROP 1 LAST TOLERANCE 10%
J 0
(7775 6975);
DISPLAY 0.617021 (7775 6975);
PAINT SKYBLUE (7775 6975);
FORCEPROP 1 LAST MATERIAL X7R
J 0
(7775 6925);
DISPLAY 0.617021 (7775 6925);
PAINT SKYBLUE (7775 6925);
FORCEPROP 1 LAST VALUE 100NF
J 0
(7775 7075);
DISPLAY 0.617021 (7775 7075);
PAINT SKYBLUE (7775 7075);
FORCEPROP 1 LAST PACK_TYPE C0402
J 0
(7775 6875);
DISPLAY 0.617021 (7775 6875);
PAINT SKYBLUE (7775 6875);
FORCEPROP 1 LAST LOCATION PC1284
J 0
(7775 7125);
DISPLAY 0.617021 (7775 7125);
PAINT AQUA (7775 7125);
FORCEPROP 1 LASTPIN (7725 7125) $PN 1
J 0
(7735 7105);
DISPLAY 0.617021 (7735 7105);
FORCEPROP 1 LASTPIN (7725 6925) $PN 2
J 0
(7735 6905);
DISPLAY 0.617021 (7735 6905);
FORCEPROP 1 LAST PATH I28
J 0
(7775 7175);
DISPLAY 0.978723 (7775 7175);
PAINT WHITE (7775 7175);
DISPLAY INVISIBLE (7775 7175);
FORCEPROP 2 LAST CDS_LIB pure_quanta
J 0
(7725 7025);
PAINT MONO (7725 7025);
DISPLAY INVISIBLE (7725 7025);
FORCEPROP 2 LAST $SEC 1
J 0
(7775 7225);
DISPLAY 0.680851 (7775 7225);
PAINT MONO (7775 7225);
DISPLAY INVISIBLE (7775 7225);
FORCEPROP 2 LAST CDS_SEC 1
J 0
(7775 7225);
DISPLAY 1.021277 (7775 7225);
DISPLAY INVISIBLE (7775 7225);
FORCEADD Q_RES..1
(7375 7725);
FORCEPROP 1 LAST PART_NUMBER CS00002JB13
J 0
(7300 7775);
DISPLAY 0.617021 (7300 7775);
PAINT BLUE (7300 7775);
DISPLAY INVISIBLE (7300 7775);
FORCEPROP 1 LAST VALUE 0
J 2
(7525 7725);
DISPLAY 0.617021 (7525 7725);
PAINT SKYBLUE (7525 7725);
FORCEPROP 1 LAST TOLERANCE 5%
J 0
(7550 7725);
DISPLAY 0.617021 (7550 7725);
PAINT SKYBLUE (7550 7725);
FORCEPROP 1 LAST PACK_TYPE 0402LF
J 0
(7525 7675);
DISPLAY 0.638298 (7525 7675);
PAINT SKYBLUE (7525 7675);
FORCEPROP 1 LAST MATERIAL CHIP
J 0
(7625 7725);
DISPLAY 0.617021 (7625 7725);
PAINT SKYBLUE (7625 7725);
FORCEPROP 1 LAST LOCATION R2387
J 0
(7125 7725);
DISPLAY 0.723404 (7125 7725);
PAINT AQUA (7125 7725);
FORCEPROP 1 LASTPIN (7275 7725) $PN 1
J 0
(7287 7737);
DISPLAY 0.617021 (7287 7737);
FORCEPROP 1 LASTPIN (7475 7725) $PN 2
J 0
(7437 7737);
DISPLAY 0.617021 (7437 7737);
FORCEPROP 1 LAST PATH I29
J 0
(7325 7875);
DISPLAY 0.978723 (7325 7875);
PAINT WHITE (7325 7875);
DISPLAY INVISIBLE (7325 7875);
FORCEPROP 1 LAST WATTAGE 1/16W
J 2
(7550 7800);
DISPLAY 0.404255 (7550 7800);
PAINT SKYBLUE (7550 7800);
DISPLAY INVISIBLE (7550 7800);
FORCEPROP 2 LAST CDS_LIB pure_quanta
J 0
(7375 7725);
PAINT MONO (7375 7725);
DISPLAY INVISIBLE (7375 7725);
FORCEPROP 2 LAST $SEC 1
J 0
(7325 7925);
DISPLAY 0.680851 (7325 7925);
PAINT MONO (7325 7925);
DISPLAY INVISIBLE (7325 7925);
FORCEPROP 2 LAST CDS_SEC 1
J 0
(7325 7925);
DISPLAY 1.021277 (7325 7925);
DISPLAY INVISIBLE (7325 7925);
FORCEADD UNIVERSAL_GND..1
(3625 5725);
FORCEPROP 3 LASTPIN (3625 5775) SIG_NAME GND\g
J 0
(3635 5785);
DISPLAY 0.659574 (3635 5785);
PAINT MONO (3635 5785);
DISPLAY INVISIBLE (3635 5785);
FORCEPROP 1 LAST PATH I3
J 0
(3700 5725);
DISPLAY 0.872340 (3700 5725);
PAINT AQUA (3700 5725);
DISPLAY INVISIBLE (3700 5725);
FORCEPROP 1 LAST HDL_POWER GND
J 1
(3650 5650);
DISPLAY 0.702128 (3650 5650);
PAINT GREEN (3650 5650);
DISPLAY INVISIBLE (3650 5650);
FORCEPROP 2 LAST CDS_LIB logical_power
J 0
(3625 5725);
DISPLAY INVISIBLE (3625 5725);
FORCEADD VCCAUX15..1
(2450 8400);
FORCEPROP 3 LASTPIN (2450 8350) SIG_NAME SW_P12V_PVCCINFAON_CPU1_FLT\g
J 0
(2460 8360);
DISPLAY 0.659574 (2460 8360);
PAINT MONO (2460 8360);
DISPLAY INVISIBLE (2460 8360);
FORCEPROP 1 LAST HDL_POWER SW_P12V_PVCCINFAON_CPU1_FLT
J 1
(2450 8442);
DISPLAY 0.617021 (2450 8442);
PAINT GREEN (2450 8442);
FORCEPROP 1 LAST PATH I30
J 0
(2500 8425);
DISPLAY 0.872340 (2500 8425);
PAINT AQUA (2500 8425);
DISPLAY INVISIBLE (2500 8425);
FORCEPROP 2 LAST CDS_LIB logical_power
J 0
(2450 8400);
DISPLAY INVISIBLE (2450 8400);
FORCEPROP 2 LAST BOM_COST VR_PCH
J 0
(2450 8475);
DISPLAY 0.680851 (2450 8475);
DISPLAY INVISIBLE (2450 8475);
FORCEADD Q_RES..2
(6350 8075);
FORCEPROP 1 LAST PART_NUMBER CS31002FB08
J 0
(6390 7950);
DISPLAY 0.617021 (6390 7950);
PAINT BLUE (6390 7950);
DISPLAY INVISIBLE (6390 7950);
FORCEPROP 1 LAST TOLERANCE 1%
J 0
(6395 8100);
DISPLAY 0.617021 (6395 8100);
PAINT SKYBLUE (6395 8100);
FORCEPROP 1 LAST MATERIAL CHIP
J 0
(6390 8000);
DISPLAY 0.617021 (6390 8000);
PAINT SKYBLUE (6390 8000);
FORCEPROP 1 LAST PACK_TYPE 0402LF
J 0
(6390 7900);
DISPLAY 0.617021 (6390 7900);
PAINT SKYBLUE (6390 7900);
FORCEPROP 1 LAST VALUE 10K
J 0
(6395 8150);
DISPLAY 0.617021 (6395 8150);
PAINT SKYBLUE (6395 8150);
FORCEPROP 1 LAST WATTAGE 1/16W
J 0
(6390 8050);
DISPLAY 0.617021 (6390 8050);
PAINT SKYBLUE (6390 8050);
FORCEPROP 1 LAST LOCATION R2584
J 0
(6395 8200);
DISPLAY 0.617021 (6395 8200);
PAINT AQUA (6395 8200);
FORCEPROP 1 LASTPIN (6350 8175) $PN 1
J 0
(6355 8137);
DISPLAY 0.617021 (6355 8137);
FORCEPROP 1 LASTPIN (6350 7975) $PN 2
J 0
(6355 7985);
DISPLAY 0.617021 (6355 7985);
FORCEPROP 1 LAST PATH I31
J 0
(6400 8250);
DISPLAY 0.978723 (6400 8250);
PAINT WHITE (6400 8250);
DISPLAY INVISIBLE (6400 8250);
FORCEPROP 2 LAST BOM_COST VR_PCH
J 0
(6400 8250);
DISPLAY 0.680851 (6400 8250);
DISPLAY INVISIBLE (6400 8250);
FORCEPROP 2 LAST CDS_LIB pure_quanta
J 0
(6350 8075);
DISPLAY INVISIBLE (6350 8075);
FORCEPROP 0 LAST $SEC 1
J 0
(6400 8300);
DISPLAY 0.680851 (6400 8300);
PAINT MONO (6400 8300);
DISPLAY INVISIBLE (6400 8300);
FORCEPROP 0 LAST CDS_SEC 1
J 0
(6400 8300);
DISPLAY 0.680851 (6400 8300);
DISPLAY INVISIBLE (6400 8300);
FORCEADD UNIVERSAL_POWER..1
(6350 8325);
FORCEPROP 3 LASTPIN (6350 8275) SIG_NAME P3V3_AUX\g
J 0
(6360 8285);
DISPLAY 0.659574 (6360 8285);
PAINT MONO (6360 8285);
DISPLAY INVISIBLE (6360 8285);
FORCEPROP 1 LAST HDL_POWER P3V3_AUX
J 1
(6350 8375);
DISPLAY 0.617021 (6350 8375);
PAINT GREEN (6350 8375);
FORCEPROP 1 LAST PATH I32
J 0
(6400 8350);
DISPLAY 0.872340 (6400 8350);
PAINT AQUA (6400 8350);
DISPLAY INVISIBLE (6400 8350);
FORCEPROP 2 LAST CDS_LIB logical_power
J 0
(6350 8325);
DISPLAY INVISIBLE (6350 8325);
FORCEADD Q_CAP..2
(8075 6025);
FORCEPROP 1 LAST PART_NUMBER TMP_QCH16806KB17
J 1
(8425 5925);
DISPLAY 0.617021 (8425 5925);
PAINT BLUE (8425 5925);
DISPLAY INVISIBLE (8425 5925);
FORCEPROP 1 LAST MATERIAL X7R
J 0
(8075 5875);
DISPLAY 0.617021 (8075 5875);
PAINT SKYBLUE (8075 5875);
FORCEPROP 1 LAST VOLTAGE 50V
J 0
(8075 5925);
DISPLAY 0.617021 (8075 5925);
PAINT SKYBLUE (8075 5925);
FORCEPROP 1 LAST VALUE 680PF
J 2
(8075 5925);
DISPLAY 0.617021 (8075 5925);
PAINT SKYBLUE (8075 5925);
FORCEPROP 1 LAST TOLERANCE 10%
J 2
(8075 5875);
DISPLAY 0.617021 (8075 5875);
PAINT SKYBLUE (8075 5875);
FORCEPROP 1 LAST PACK_TYPE 0402
J 1
(8075 5825);
DISPLAY 0.617021 (8075 5825);
PAINT SKYBLUE (8075 5825);
FORCEPROP 1 LAST LOCATION PC238
J 1
(8075 6075);
DISPLAY 0.617021 (8075 6075);
PAINT AQUA (8075 6075);
FORCEPROP 1 LAST PATH I33
J 0
(8075 6225);
DISPLAY 0.978723 (8075 6225);
PAINT WHITE (8075 6225);
DISPLAY INVISIBLE (8075 6225);
FORCEPROP 2 LAST CDS_LIB pure_quanta
J 0
(8075 6025);
DISPLAY INVISIBLE (8075 6025);
FORCEPROP 0 LAST $SEC 1
J 0
(7900 6100);
DISPLAY 0.680851 (7900 6100);
PAINT MONO (7900 6100);
DISPLAY INVISIBLE (7900 6100);
FORCEPROP 0 LAST CDS_SEC 1
J 0
(7900 6100);
DISPLAY 1.021277 (7900 6100);
DISPLAY INVISIBLE (7900 6100);
FORCEPROP 1 LASTPIN (7975 6025) $PN 1
J 0
(7965 6040);
DISPLAY 0.808511 (7965 6040);
PAINT WHITE (7965 6040);
DISPLAY INVISIBLE (7965 6040);
FORCEPROP 1 LASTPIN (8175 6025) $PN 2
J 0
(8160 6040);
DISPLAY 0.808511 (8160 6040);
PAINT WHITE (8160 6040);
DISPLAY INVISIBLE (8160 6040);
FORCEADD Q_RES..1
(8075 6375);
FORCEPROP 1 LAST PART_NUMBER CS28252BB01
J 0
(8025 6475);
DISPLAY 0.617021 (8025 6475);
PAINT BLUE (8025 6475);
DISPLAY INVISIBLE (8025 6475);
FORCEPROP 1 LAST VALUE 8.25K
J 2
(8050 6275);
DISPLAY 0.617021 (8050 6275);
PAINT SKYBLUE (8050 6275);
FORCEPROP 1 LAST WATTAGE 1/16W
J 2
(8050 6225);
DISPLAY 0.617021 (8050 6225);
PAINT SKYBLUE (8050 6225);
FORCEPROP 1 LAST PACK_TYPE 0402LF
J 0
(8250 6225);
DISPLAY 0.617021 (8250 6225);
PAINT SKYBLUE (8250 6225);
FORCEPROP 1 LAST TOLERANCE 0.1%
J 0
(8075 6275);
DISPLAY 0.617021 (8075 6275);
PAINT SKYBLUE (8075 6275);
FORCEPROP 1 LAST MATERIAL CHIP
J 0
(8075 6225);
DISPLAY 0.617021 (8075 6225);
PAINT SKYBLUE (8075 6225);
FORCEPROP 1 LAST LOCATION PR502
J 0
(8025 6425);
DISPLAY 0.617021 (8025 6425);
PAINT AQUA (8025 6425);
FORCEPROP 1 LASTPIN (7975 6375) $PN 1
J 0
(7987 6387);
DISPLAY 0.617021 (7987 6387);
PAINT MONO (7987 6387);
FORCEPROP 1 LASTPIN (8175 6375) $PN 2
J 0
(8137 6387);
DISPLAY 0.617021 (8137 6387);
PAINT MONO (8137 6387);
FORCEPROP 1 LAST PATH I34
J 0
(8025 6525);
DISPLAY 0.978723 (8025 6525);
PAINT WHITE (8025 6525);
DISPLAY INVISIBLE (8025 6525);
FORCEPROP 2 LAST CDS_LIB pure_quanta
J 0
(8075 6375);
DISPLAY INVISIBLE (8075 6375);
FORCEPROP 0 LAST $SEC 1
J 0
(8025 6525);
DISPLAY 0.680851 (8025 6525);
PAINT MONO (8025 6525);
DISPLAY INVISIBLE (8025 6525);
FORCEPROP 0 LAST CDS_SEC 1
J 0
(8025 6525);
DISPLAY 1.021277 (8025 6525);
DISPLAY INVISIBLE (8025 6525);
FORCEADD UNIVERSAL_GND..1
(7875 7325);
FORCEPROP 3 LASTPIN (7875 7375) SIG_NAME GND\g
J 0
(7885 7385);
DISPLAY 0.659574 (7885 7385);
PAINT MONO (7885 7385);
DISPLAY INVISIBLE (7885 7385);
FORCEPROP 1 LAST PATH I35
J 0
(7950 7325);
DISPLAY 0.872340 (7950 7325);
PAINT AQUA (7950 7325);
DISPLAY INVISIBLE (7950 7325);
FORCEPROP 1 LAST HDL_POWER GND
J 1
(7900 7250);
DISPLAY 0.872340 (7900 7250);
PAINT GREEN (7900 7250);
DISPLAY INVISIBLE (7900 7250);
FORCEPROP 2 LAST CDS_LIB logical_power
J 0
(7875 7325);
PAINT MONO (7875 7325);
DISPLAY INVISIBLE (7875 7325);
FORCEADD Q_CAP..1
(8125 7025);
FORCEPROP 1 LAST PART_NUMBER CH622KMEA03
J 0
(8175 6825);
DISPLAY 0.617021 (8175 6825);
PAINT BLUE (8175 6825);
DISPLAY INVISIBLE (8175 6825);
FORCEPROP 1 LAST PACK_TYPE C0805
J 0
(8175 6875);
DISPLAY 0.617021 (8175 6875);
PAINT SKYBLUE (8175 6875);
FORCEPROP 1 LAST MATERIAL X6S
J 0
(8175 6925);
DISPLAY 0.617021 (8175 6925);
PAINT SKYBLUE (8175 6925);
FORCEPROP 1 LAST VALUE 22UF
J 0
(8175 7075);
DISPLAY 0.617021 (8175 7075);
PAINT SKYBLUE (8175 7075);
FORCEPROP 1 LAST VOLTAGE 4V
J 0
(8175 7025);
DISPLAY 0.617021 (8175 7025);
PAINT SKYBLUE (8175 7025);
FORCEPROP 1 LAST TOLERANCE 20%
J 0
(8175 6975);
DISPLAY 0.617021 (8175 6975);
PAINT SKYBLUE (8175 6975);
FORCEPROP 1 LAST LOCATION PC1285
J 0
(8175 7125);
DISPLAY 0.617021 (8175 7125);
PAINT AQUA (8175 7125);
FORCEPROP 1 LASTPIN (8125 7125) $PN 1
J 0
(8135 7105);
DISPLAY 0.617021 (8135 7105);
FORCEPROP 1 LASTPIN (8125 6925) $PN 2
J 0
(8135 6905);
DISPLAY 0.617021 (8135 6905);
FORCEPROP 1 LAST PATH I36
J 0
(8175 7175);
DISPLAY 0.978723 (8175 7175);
PAINT WHITE (8175 7175);
DISPLAY INVISIBLE (8175 7175);
FORCEPROP 2 LAST CDS_LIB pure_quanta
J 0
(8125 7025);
PAINT MONO (8125 7025);
DISPLAY INVISIBLE (8125 7025);
FORCEPROP 2 LAST BOM_COST VR_PCH
J 0
(8175 7175);
DISPLAY 0.680851 (8175 7175);
DISPLAY INVISIBLE (8175 7175);
FORCEPROP 2 LAST $SEC 1
J 0
(8175 7225);
DISPLAY 0.680851 (8175 7225);
PAINT MONO (8175 7225);
DISPLAY INVISIBLE (8175 7225);
FORCEPROP 2 LAST CDS_SEC 1
J 0
(8175 7225);
DISPLAY 1.021277 (8175 7225);
DISPLAY INVISIBLE (8175 7225);
FORCEADD Q_CAP..1
(7875 7550);
FORCEPROP 1 LAST PART_NUMBER TMP_QCH21006JB10
J 0
(7925 7400);
DISPLAY 0.617021 (7925 7400);
PAINT BLUE (7925 7400);
DISPLAY INVISIBLE (7925 7400);
FORCEPROP 1 LAST PACK_TYPE 0402
J 0
(7925 7350);
DISPLAY 0.617021 (7925 7350);
PAINT SKYBLUE (7925 7350);
FORCEPROP 1 LAST VALUE 1000PF
J 0
(7925 7600);
DISPLAY 0.617021 (7925 7600);
PAINT SKYBLUE (7925 7600);
FORCEPROP 1 LAST VOLTAGE 50V
J 0
(7925 7550);
DISPLAY 0.617021 (7925 7550);
PAINT SKYBLUE (7925 7550);
FORCEPROP 1 LAST TOLERANCE 5%
J 0
(7925 7500);
DISPLAY 0.617021 (7925 7500);
PAINT SKYBLUE (7925 7500);
FORCEPROP 1 LAST MATERIAL X7R
J 0
(7925 7450);
DISPLAY 0.617021 (7925 7450);
PAINT SKYBLUE (7925 7450);
FORCEPROP 1 LAST LOCATION C1297
J 0
(7925 7650);
DISPLAY 0.723404 (7925 7650);
PAINT AQUA (7925 7650);
FORCEPROP 1 LASTPIN (7875 7650) $PN 1
J 0
(7885 7630);
DISPLAY 0.617021 (7885 7630);
FORCEPROP 1 LASTPIN (7875 7450) $PN 2
J 0
(7885 7430);
DISPLAY 0.617021 (7885 7430);
FORCEPROP 1 LAST PATH I37
J 0
(7925 7700);
DISPLAY 0.978723 (7925 7700);
PAINT WHITE (7925 7700);
DISPLAY INVISIBLE (7925 7700);
FORCEPROP 2 LAST CDS_LIB pure_quanta
J 0
(7875 7550);
PAINT MONO (7875 7550);
DISPLAY INVISIBLE (7875 7550);
FORCEPROP 2 LAST $SEC 1
J 0
(7925 7750);
DISPLAY 0.680851 (7925 7750);
PAINT MONO (7925 7750);
DISPLAY INVISIBLE (7925 7750);
FORCEPROP 2 LAST CDS_SEC 1
J 0
(7925 7750);
DISPLAY 1.021277 (7925 7750);
DISPLAY INVISIBLE (7925 7750);
FORCEADD Q_CAP..1
(8500 7025);
FORCEPROP 1 LAST PART_NUMBER CH622KMEA03
J 0
(8550 6825);
DISPLAY 0.617021 (8550 6825);
PAINT BLUE (8550 6825);
DISPLAY INVISIBLE (8550 6825);
FORCEPROP 1 LAST VALUE 22UF
J 0
(8550 7075);
DISPLAY 0.617021 (8550 7075);
PAINT SKYBLUE (8550 7075);
FORCEPROP 1 LAST VOLTAGE 4V
J 0
(8550 7025);
DISPLAY 0.617021 (8550 7025);
PAINT SKYBLUE (8550 7025);
FORCEPROP 1 LAST MATERIAL X6S
J 0
(8550 6925);
DISPLAY 0.617021 (8550 6925);
PAINT SKYBLUE (8550 6925);
FORCEPROP 1 LAST TOLERANCE 20%
J 0
(8550 6975);
DISPLAY 0.617021 (8550 6975);
PAINT SKYBLUE (8550 6975);
FORCEPROP 1 LAST PACK_TYPE C0805
J 0
(8550 6875);
DISPLAY 0.617021 (8550 6875);
PAINT SKYBLUE (8550 6875);
FORCEPROP 1 LAST LOCATION PC1286
J 0
(8550 7125);
DISPLAY 0.617021 (8550 7125);
PAINT AQUA (8550 7125);
FORCEPROP 1 LASTPIN (8500 7125) $PN 1
J 0
(8510 7105);
DISPLAY 0.617021 (8510 7105);
FORCEPROP 1 LASTPIN (8500 6925) $PN 2
J 0
(8510 6905);
DISPLAY 0.617021 (8510 6905);
FORCEPROP 1 LAST PATH I38
J 0
(8550 7175);
DISPLAY 0.978723 (8550 7175);
PAINT WHITE (8550 7175);
DISPLAY INVISIBLE (8550 7175);
FORCEPROP 2 LAST CDS_LIB pure_quanta
J 0
(8500 7025);
PAINT MONO (8500 7025);
DISPLAY INVISIBLE (8500 7025);
FORCEPROP 2 LAST BOM_COST VR_PCH
J 0
(8550 7175);
DISPLAY 0.680851 (8550 7175);
DISPLAY INVISIBLE (8550 7175);
FORCEPROP 2 LAST $SEC 1
J 0
(8550 7225);
DISPLAY 0.680851 (8550 7225);
PAINT MONO (8550 7225);
DISPLAY INVISIBLE (8550 7225);
FORCEPROP 2 LAST CDS_SEC 1
J 0
(8550 7225);
DISPLAY 1.021277 (8550 7225);
DISPLAY INVISIBLE (8550 7225);
FORCEADD OFFPAGE..2
(8775 7725);
FORCEPROP 2 LAST $XR1 254 
J 0
(9084 7725);
DISPLAY 0.638298 (9084 7725);
PAINT MONO (9084 7725);
FORCEPROP 2 LAST $XR0 213 
J 0
(8964 7725);
DISPLAY 0.638298 (8964 7725);
PAINT MONO (8964 7725);
FORCEPROP 2 LAST PATH I39
J 0
(9100 7775);
DISPLAY 1.021277 (9100 7775);
DISPLAY INVISIBLE (9100 7775);
FORCEPROP 1 LAST COMMENT_BODY TRUE
J 0
(8730 7630);
DISPLAY 0.531915 (8730 7630);
PAINT GREEN (8730 7630);
DISPLAY INVISIBLE (8730 7630);
FORCEPROP 1 LAST OFFPAGE TRUE
J 0
(9100 7600);
DISPLAY 0.531915 (9100 7600);
PAINT GREEN (9100 7600);
DISPLAY INVISIBLE (9100 7600);
FORCEPROP 2 LAST CDS_LIB standard
J 0
(8775 7725);
PAINT MONO (8775 7725);
DISPLAY INVISIBLE (8775 7725);
FORCEPROP 2 LAST BOM_COST VR_SYSTEM
J 0
(9125 7775);
DISPLAY 0.680851 (9125 7775);
DISPLAY INVISIBLE (9125 7775);
FORCEADD UNIVERSAL_GND..1
(2500 6800);
FORCEPROP 3 LASTPIN (2500 6850) SIG_NAME GND\g
J 0
(2510 6860);
DISPLAY 0.659574 (2510 6860);
PAINT MONO (2510 6860);
DISPLAY INVISIBLE (2510 6860);
FORCEPROP 1 LAST PATH I4
J 0
(2575 6800);
DISPLAY 0.872340 (2575 6800);
PAINT AQUA (2575 6800);
DISPLAY INVISIBLE (2575 6800);
FORCEPROP 1 LAST HDL_POWER GND
J 1
(2525 6725);
DISPLAY 0.872340 (2525 6725);
PAINT GREEN (2525 6725);
DISPLAY INVISIBLE (2525 6725);
FORCEPROP 2 LAST CDS_LIB logical_power
J 0
(2500 6800);
PAINT MONO (2500 6800);
DISPLAY INVISIBLE (2500 6800);
FORCEADD Q_CAP..1
(8775 6100);
FORCEPROP 1 LAST PART_NUMBER TMP_QCH31004KB17
J 0
(8825 5950);
DISPLAY 0.617021 (8825 5950);
PAINT BLUE (8825 5950);
DISPLAY INVISIBLE (8825 5950);
FORCEPROP 1 LAST VALUE 0.01UF
J 0
(8825 6150);
DISPLAY 0.617021 (8825 6150);
PAINT SKYBLUE (8825 6150);
FORCEPROP 1 LAST TOLERANCE 10%
J 0
(8825 6050);
DISPLAY 0.617021 (8825 6050);
PAINT SKYBLUE (8825 6050);
FORCEPROP 1 LAST PACK_TYPE 0402
J 0
(8825 5900);
DISPLAY 0.617021 (8825 5900);
PAINT SKYBLUE (8825 5900);
FORCEPROP 1 LAST VOLTAGE 25V
J 0
(8825 6100);
DISPLAY 0.617021 (8825 6100);
PAINT SKYBLUE (8825 6100);
FORCEPROP 1 LAST MATERIAL X7R
J 0
(8825 6000);
DISPLAY 0.617021 (8825 6000);
PAINT RED (8825 6000);
FORCEPROP 1 LAST LOCATION PC2277
J 0
(8825 6200);
DISPLAY 0.617021 (8825 6200);
PAINT AQUA (8825 6200);
FORCEPROP 1 LASTPIN (8775 6200) $PN 1
J 0
(8785 6180);
DISPLAY 0.787234 (8785 6180);
PAINT MONO (8785 6180);
FORCEPROP 1 LASTPIN (8775 6000) $PN 2
J 0
(8785 5980);
DISPLAY 0.787234 (8785 5980);
PAINT MONO (8785 5980);
FORCEPROP 1 LAST PATH I40
J 0
(8825 6250);
DISPLAY 0.978723 (8825 6250);
PAINT WHITE (8825 6250);
DISPLAY INVISIBLE (8825 6250);
FORCEPROP 2 LAST CDS_LIB pure_quanta
J 0
(8775 6100);
DISPLAY INVISIBLE (8775 6100);
FORCEPROP 0 LAST $SEC 1
J 0
(8825 6250);
DISPLAY 0.680851 (8825 6250);
PAINT MONO (8825 6250);
DISPLAY INVISIBLE (8825 6250);
FORCEPROP 0 LAST CDS_SEC 1
J 0
(8825 6250);
DISPLAY 1.021277 (8825 6250);
DISPLAY INVISIBLE (8825 6250);
FORCEADD UNIVERSAL_GND..1
(8875 6650);
FORCEPROP 3 LASTPIN (8875 6700) SIG_NAME GND\g
J 0
(8885 6710);
DISPLAY 0.659574 (8885 6710);
PAINT MONO (8885 6710);
DISPLAY INVISIBLE (8885 6710);
FORCEPROP 1 LAST PATH I41
J 0
(8950 6650);
DISPLAY 0.872340 (8950 6650);
PAINT AQUA (8950 6650);
DISPLAY INVISIBLE (8950 6650);
FORCEPROP 2 LAST CDS_LIB logical_power
J 0
(8875 6650);
DISPLAY INVISIBLE (8875 6650);
FORCEPROP 1 LAST HDL_POWER GND
J 1
(8900 6575);
DISPLAY 0.872340 (8900 6575);
PAINT GREEN (8900 6575);
DISPLAY INVISIBLE (8900 6575);
FORCEADD Q_RES..1
(9400 6125);
FORCEPROP 1 LAST PART_NUMBER CS00002JB13
J 0
(9250 6050);
DISPLAY 0.617021 (9250 6050);
PAINT BLUE (9250 6050);
DISPLAY INVISIBLE (9250 6050);
FORCEPROP 1 LAST PACK_TYPE 0402LF
J 0
(9425 6000);
DISPLAY 0.638298 (9425 6000);
PAINT SKYBLUE (9425 6000);
FORCEPROP 1 LAST MATERIAL EMPTY
J 0
(9250 6000);
DISPLAY 0.617021 (9250 6000);
PAINT RED (9250 6000);
FORCEPROP 1 LAST TOLERANCE 5%
J 0
(9450 6175);
DISPLAY 0.617021 (9450 6175);
PAINT SKYBLUE (9450 6175);
FORCEPROP 1 LAST VALUE 0
J 2
(9375 6175);
DISPLAY 0.617021 (9375 6175);
PAINT SKYBLUE (9375 6175);
FORCEPROP 1 LAST LOCATION PR4700
J 0
(9525 6125);
DISPLAY 0.978723 (9525 6125);
FORCEPROP 1 LASTPIN (9300 6125) $PN 1
J 0
(9312 6137);
DISPLAY 0.787234 (9312 6137);
PAINT MONO (9312 6137);
FORCEPROP 1 LASTPIN (9500 6125) $PN 2
J 0
(9462 6137);
DISPLAY 0.787234 (9462 6137);
PAINT MONO (9462 6137);
FORCEPROP 1 LAST PATH I42
J 0
(9350 6275);
DISPLAY 0.978723 (9350 6275);
PAINT WHITE (9350 6275);
DISPLAY INVISIBLE (9350 6275);
FORCEPROP 2 LAST CDS_LIB pure_quanta
J 0
(9400 6125);
DISPLAY INVISIBLE (9400 6125);
FORCEPROP 1 LAST WATTAGE 1/16W
J 2
(9575 6200);
DISPLAY 0.404255 (9575 6200);
PAINT SKYBLUE (9575 6200);
DISPLAY INVISIBLE (9575 6200);
FORCEPROP 0 LAST $SEC 1
J 0
(9450 6225);
DISPLAY 0.680851 (9450 6225);
PAINT MONO (9450 6225);
DISPLAY INVISIBLE (9450 6225);
FORCEPROP 0 LAST CDS_SEC 1
J 0
(9450 6225);
DISPLAY 1.021277 (9450 6225);
DISPLAY INVISIBLE (9450 6225);
FORCEADD Q_RES..1
(9400 6375);
FORCEPROP 1 LAST PART_NUMBER CS00002JB13
J 0
(9250 6300);
DISPLAY 0.617021 (9250 6300);
PAINT BLUE (9250 6300);
DISPLAY INVISIBLE (9250 6300);
FORCEPROP 1 LAST TOLERANCE 5%
J 0
(9450 6425);
DISPLAY 0.617021 (9450 6425);
PAINT SKYBLUE (9450 6425);
FORCEPROP 1 LAST VALUE 0
J 2
(9375 6425);
DISPLAY 0.617021 (9375 6425);
PAINT SKYBLUE (9375 6425);
FORCEPROP 1 LAST MATERIAL CHIP
J 0
(9250 6250);
DISPLAY 0.617021 (9250 6250);
PAINT SKYBLUE (9250 6250);
FORCEPROP 1 LAST PACK_TYPE 0402LF
J 0
(9425 6250);
DISPLAY 0.638298 (9425 6250);
PAINT SKYBLUE (9425 6250);
FORCEPROP 1 LAST LOCATION PR4699
J 0
(9525 6375);
DISPLAY 0.978723 (9525 6375);
FORCEPROP 1 LASTPIN (9300 6375) $PN 1
J 0
(9312 6387);
DISPLAY 0.787234 (9312 6387);
PAINT MONO (9312 6387);
FORCEPROP 1 LASTPIN (9500 6375) $PN 2
J 0
(9462 6387);
DISPLAY 0.787234 (9462 6387);
PAINT MONO (9462 6387);
FORCEPROP 1 LAST PATH I43
J 0
(9350 6525);
DISPLAY 0.978723 (9350 6525);
PAINT WHITE (9350 6525);
DISPLAY INVISIBLE (9350 6525);
FORCEPROP 1 LAST WATTAGE 1/16W
J 2
(9575 6450);
DISPLAY 0.404255 (9575 6450);
PAINT SKYBLUE (9575 6450);
DISPLAY INVISIBLE (9575 6450);
FORCEPROP 2 LAST CDS_LIB pure_quanta
J 0
(9400 6375);
DISPLAY INVISIBLE (9400 6375);
FORCEPROP 0 LAST $SEC 1
J 0
(9450 6475);
DISPLAY 0.680851 (9450 6475);
PAINT MONO (9450 6475);
DISPLAY INVISIBLE (9450 6475);
FORCEPROP 0 LAST CDS_SEC 1
J 0
(9450 6475);
DISPLAY 1.021277 (9450 6475);
DISPLAY INVISIBLE (9450 6475);
FORCEADD Q_CAP..1
(8875 7025);
FORCEPROP 1 LAST PART_NUMBER CH622KMEA03
J 0
(8925 6825);
DISPLAY 0.617021 (8925 6825);
PAINT BLUE (8925 6825);
DISPLAY INVISIBLE (8925 6825);
FORCEPROP 1 LAST MATERIAL X6S
J 0
(8925 6925);
DISPLAY 0.617021 (8925 6925);
PAINT SKYBLUE (8925 6925);
FORCEPROP 1 LAST VALUE 22UF
J 0
(8925 7075);
DISPLAY 0.617021 (8925 7075);
PAINT SKYBLUE (8925 7075);
FORCEPROP 1 LAST VOLTAGE 4V
J 0
(8925 7025);
DISPLAY 0.617021 (8925 7025);
PAINT SKYBLUE (8925 7025);
FORCEPROP 1 LAST TOLERANCE 20%
J 0
(8925 6975);
DISPLAY 0.617021 (8925 6975);
PAINT SKYBLUE (8925 6975);
FORCEPROP 1 LAST PACK_TYPE C0805
J 0
(8925 6875);
DISPLAY 0.617021 (8925 6875);
PAINT SKYBLUE (8925 6875);
FORCEPROP 1 LAST LOCATION PC1287
J 0
(8925 7125);
DISPLAY 0.617021 (8925 7125);
PAINT AQUA (8925 7125);
FORCEPROP 1 LASTPIN (8875 7125) $PN 1
J 0
(8885 7105);
DISPLAY 0.617021 (8885 7105);
FORCEPROP 1 LASTPIN (8875 6925) $PN 2
J 0
(8885 6905);
DISPLAY 0.617021 (8885 6905);
FORCEPROP 1 LAST PATH I44
J 0
(8925 7175);
DISPLAY 0.978723 (8925 7175);
PAINT WHITE (8925 7175);
DISPLAY INVISIBLE (8925 7175);
FORCEPROP 2 LAST CDS_LIB pure_quanta
J 0
(8875 7025);
PAINT MONO (8875 7025);
DISPLAY INVISIBLE (8875 7025);
FORCEPROP 2 LAST BOM_COST VR_PCH
J 0
(8925 7175);
DISPLAY 0.680851 (8925 7175);
DISPLAY INVISIBLE (8925 7175);
FORCEPROP 2 LAST $SEC 1
J 0
(8925 7225);
DISPLAY 0.680851 (8925 7225);
PAINT MONO (8925 7225);
DISPLAY INVISIBLE (8925 7225);
FORCEPROP 2 LAST CDS_SEC 1
J 0
(8925 7225);
DISPLAY 1.021277 (8925 7225);
DISPLAY INVISIBLE (8925 7225);
FORCEADD Q_CAP..1
(9250 7025);
FORCEPROP 1 LAST PART_NUMBER CH622KMEA03
J 0
(9300 6825);
DISPLAY 0.617021 (9300 6825);
PAINT BLUE (9300 6825);
DISPLAY INVISIBLE (9300 6825);
FORCEPROP 1 LAST MATERIAL X6S
J 0
(9300 6925);
DISPLAY 0.617021 (9300 6925);
PAINT SKYBLUE (9300 6925);
FORCEPROP 1 LAST TOLERANCE 20%
J 0
(9300 6975);
DISPLAY 0.617021 (9300 6975);
PAINT SKYBLUE (9300 6975);
FORCEPROP 1 LAST VOLTAGE 4V
J 0
(9300 7025);
DISPLAY 0.617021 (9300 7025);
PAINT SKYBLUE (9300 7025);
FORCEPROP 1 LAST VALUE 22UF
J 0
(9300 7075);
DISPLAY 0.617021 (9300 7075);
PAINT SKYBLUE (9300 7075);
FORCEPROP 1 LAST PACK_TYPE C0805
J 0
(9300 6875);
DISPLAY 0.617021 (9300 6875);
PAINT SKYBLUE (9300 6875);
FORCEPROP 1 LAST LOCATION PC1207
J 0
(9300 7125);
DISPLAY 0.617021 (9300 7125);
PAINT AQUA (9300 7125);
FORCEPROP 1 LASTPIN (9250 7125) $PN 1
J 0
(9260 7105);
DISPLAY 0.617021 (9260 7105);
PAINT MONO (9260 7105);
FORCEPROP 1 LASTPIN (9250 6925) $PN 2
J 0
(9260 6905);
DISPLAY 0.617021 (9260 6905);
PAINT MONO (9260 6905);
FORCEPROP 1 LAST PATH I45
J 0
(9300 7175);
DISPLAY 0.978723 (9300 7175);
PAINT WHITE (9300 7175);
DISPLAY INVISIBLE (9300 7175);
FORCEPROP 2 LAST CDS_LIB pure_quanta
J 0
(9250 7025);
DISPLAY INVISIBLE (9250 7025);
FORCEPROP 2 LAST BOM_COST VR_PCH
J 0
(9300 7175);
DISPLAY 0.680851 (9300 7175);
DISPLAY INVISIBLE (9300 7175);
FORCEPROP 2 LAST $SEC 1
J 0
(9300 7225);
DISPLAY 0.680851 (9300 7225);
PAINT MONO (9300 7225);
DISPLAY INVISIBLE (9300 7225);
FORCEPROP 2 LAST CDS_SEC 1
J 0
(9300 7225);
DISPLAY 1.021277 (9300 7225);
DISPLAY INVISIBLE (9300 7225);
FORCEADD UNIVERSAL_GND..1
(9925 5450);
FORCEPROP 3 LASTPIN (9925 5500) SIG_NAME GND\g
J 0
(9935 5510);
DISPLAY 0.659574 (9935 5510);
PAINT MONO (9935 5510);
DISPLAY INVISIBLE (9935 5510);
FORCEPROP 1 LAST PATH I46
J 0
(10000 5450);
DISPLAY 0.872340 (10000 5450);
PAINT AQUA (10000 5450);
DISPLAY INVISIBLE (10000 5450);
FORCEPROP 2 LAST CDS_LIB logical_power
J 0
(9925 5450);
DISPLAY INVISIBLE (9925 5450);
FORCEPROP 1 LAST HDL_POWER GND
J 1
(9950 5375);
DISPLAY 0.872340 (9950 5375);
PAINT GREEN (9950 5375);
DISPLAY INVISIBLE (9950 5375);
FORCEADD UNIVERSAL_POWER..1
(9950 6225);
FORCEPROP 3 LASTPIN (9950 6175) SIG_NAME PVNN_MAIN_CPU1\g
J 0
(9960 6185);
DISPLAY 0.659574 (9960 6185);
PAINT MONO (9960 6185);
DISPLAY INVISIBLE (9960 6185);
FORCEPROP 1 LAST HDL_POWER PVNN_MAIN_CPU1
J 1
(9950 6275);
DISPLAY 0.617021 (9950 6275);
PAINT GREEN (9950 6275);
FORCEPROP 1 LAST PATH I47
J 0
(10000 6250);
DISPLAY 0.872340 (10000 6250);
PAINT AQUA (10000 6250);
DISPLAY INVISIBLE (10000 6250);
FORCEPROP 2 LAST CDS_LIB logical_power
J 0
(9950 6225);
DISPLAY INVISIBLE (9950 6225);
FORCEADD UNIVERSAL_POWER..1
(9950 7400);
FORCEPROP 3 LASTPIN (9950 7350) SIG_NAME PVNN_MAIN_CPU1\g
J 0
(9960 7360);
DISPLAY 0.659574 (9960 7360);
PAINT MONO (9960 7360);
DISPLAY INVISIBLE (9960 7360);
FORCEPROP 1 LAST HDL_POWER PVNN_MAIN_CPU1
J 1
(9950 7450);
DISPLAY 0.617021 (9950 7450);
PAINT GREEN (9950 7450);
FORCEPROP 1 LAST PATH I48
J 0
(10000 7425);
DISPLAY 0.872340 (10000 7425);
PAINT AQUA (10000 7425);
DISPLAY INVISIBLE (10000 7425);
FORCEPROP 2 LAST CDS_LIB logical_power
J 0
(9950 7400);
DISPLAY INVISIBLE (9950 7400);
FORCEADD Q_RES..1
(1925 7400);
FORCEPROP 1 LAST PART_NUMBER CS31002FB08
J 0
(1775 7475);
DISPLAY 0.617021 (1775 7475);
PAINT BLUE (1775 7475);
DISPLAY INVISIBLE (1775 7475);
FORCEPROP 1 LAST TOLERANCE 1%
J 0
(2175 7400);
DISPLAY 0.617021 (2175 7400);
PAINT SKYBLUE (2175 7400);
FORCEPROP 1 LAST MATERIAL EMPTY
J 0
(2250 7400);
DISPLAY 0.617021 (2250 7400);
PAINT RED (2250 7400);
FORCEPROP 1 LAST PACK_TYPE 0402LF
J 0
(1775 7525);
DISPLAY 0.617021 (1775 7525);
PAINT SKYBLUE (1775 7525);
FORCEPROP 1 LAST WATTAGE 1/16W
J 2
(2175 7525);
DISPLAY 0.617021 (2175 7525);
PAINT SKYBLUE (2175 7525);
FORCEPROP 1 LAST VALUE 10K
J 2
(2150 7400);
DISPLAY 0.617021 (2150 7400);
PAINT SKYBLUE (2150 7400);
FORCEPROP 1 LAST LOCATION R2384
J 0
(1675 7400);
DISPLAY 0.723404 (1675 7400);
PAINT AQUA (1675 7400);
FORCEPROP 1 LASTPIN (1825 7400) $PN 1
J 0
(1837 7412);
DISPLAY 0.617021 (1837 7412);
FORCEPROP 1 LASTPIN (2025 7400) $PN 2
J 0
(1987 7412);
DISPLAY 0.617021 (1987 7412);
FORCEPROP 1 LAST PATH I5
J 0
(1875 7550);
DISPLAY 0.978723 (1875 7550);
PAINT WHITE (1875 7550);
DISPLAY INVISIBLE (1875 7550);
FORCEPROP 2 LAST CDS_LIB pure_quanta
J 0
(1925 7400);
PAINT MONO (1925 7400);
DISPLAY INVISIBLE (1925 7400);
FORCEPROP 2 LAST $SEC 1
J 0
(1875 7600);
DISPLAY 0.680851 (1875 7600);
PAINT MONO (1875 7600);
DISPLAY INVISIBLE (1875 7600);
FORCEPROP 2 LAST CDS_SEC 1
J 0
(1875 7600);
DISPLAY 1.021277 (1875 7600);
DISPLAY INVISIBLE (1875 7600);
FORCEADD Q_CAP..1
R 2
(2400 7025);
FORCEPROP 1 LAST PART_NUMBER TMP_QCH21006JB10
J 2
(2350 6900);
DISPLAY 0.617021 (2350 6900);
PAINT BLUE (2350 6900);
DISPLAY INVISIBLE (2350 6900);
FORCEPROP 1 LAST VOLTAGE 50V
J 2
(2350 7050);
DISPLAY 0.617021 (2350 7050);
PAINT SKYBLUE (2350 7050);
FORCEPROP 1 LAST VALUE 1000PF
J 2
(2350 7100);
DISPLAY 0.617021 (2350 7100);
PAINT SKYBLUE (2350 7100);
FORCEPROP 1 LAST TOLERANCE 5%
J 2
(2350 7000);
DISPLAY 0.617021 (2350 7000);
PAINT SKYBLUE (2350 7000);
FORCEPROP 1 LAST MATERIAL EMPTY
J 2
(2350 6950);
DISPLAY 0.617021 (2350 6950);
PAINT RED (2350 6950);
FORCEPROP 1 LAST PACK_TYPE 0402
J 2
(2350 6850);
DISPLAY 0.617021 (2350 6850);
PAINT SKYBLUE (2350 6850);
FORCEPROP 1 LAST LOCATION C1308
J 2
(2350 7150);
DISPLAY 0.723404 (2350 7150);
PAINT AQUA (2350 7150);
FORCEPROP 1 LASTPIN (2400 7125) $PN 1
J 2
(2390 7105);
DISPLAY 0.617021 (2390 7105);
FORCEPROP 1 LASTPIN (2400 6925) $PN 2
J 2
(2390 6905);
DISPLAY 0.617021 (2390 6905);
FORCEPROP 1 LAST PATH I6
J 2
(2350 7175);
DISPLAY 0.978723 (2350 7175);
PAINT WHITE (2350 7175);
DISPLAY INVISIBLE (2350 7175);
FORCEPROP 2 LAST CDS_LIB pure_quanta
J 0
(2400 7025);
PAINT MONO (2400 7025);
DISPLAY INVISIBLE (2400 7025);
FORCEPROP 2 LAST $SEC 1
J 0
(2350 7225);
DISPLAY 0.680851 (2350 7225);
PAINT MONO (2350 7225);
DISPLAY INVISIBLE (2350 7225);
FORCEPROP 2 LAST CDS_SEC 1
J 0
(2350 7225);
DISPLAY 1.021277 (2350 7225);
DISPLAY INVISIBLE (2350 7225);
FORCEADD Q_RES..2
(2500 7025);
FORCEPROP 1 LAST PART_NUMBER CS22002FB07
J 0
(2540 6900);
DISPLAY 0.617021 (2540 6900);
PAINT BLUE (2540 6900);
DISPLAY INVISIBLE (2540 6900);
FORCEPROP 1 LAST VALUE 2K
J 0
(2545 7100);
DISPLAY 0.617021 (2545 7100);
PAINT SKYBLUE (2545 7100);
FORCEPROP 1 LAST MATERIAL CHIP
J 0
(2540 6950);
DISPLAY 0.617021 (2540 6950);
PAINT SKYBLUE (2540 6950);
FORCEPROP 1 LAST PACK_TYPE 0402LF
J 0
(2540 6850);
DISPLAY 0.617021 (2540 6850);
PAINT SKYBLUE (2540 6850);
FORCEPROP 1 LAST WATTAGE 1/16W
J 0
(2540 7000);
DISPLAY 0.617021 (2540 7000);
PAINT SKYBLUE (2540 7000);
FORCEPROP 1 LAST TOLERANCE 1%
J 0
(2545 7050);
DISPLAY 0.617021 (2545 7050);
PAINT SKYBLUE (2545 7050);
FORCEPROP 1 LAST LOCATION R2385
J 0
(2545 7150);
DISPLAY 0.723404 (2545 7150);
PAINT AQUA (2545 7150);
FORCEPROP 1 LASTPIN (2500 7125) $PN 1
J 0
(2505 7087);
DISPLAY 0.617021 (2505 7087);
FORCEPROP 1 LASTPIN (2500 6925) $PN 2
J 0
(2505 6935);
DISPLAY 0.617021 (2505 6935);
FORCEPROP 1 LAST PATH I7
J 0
(2550 7200);
DISPLAY 0.978723 (2550 7200);
PAINT WHITE (2550 7200);
DISPLAY INVISIBLE (2550 7200);
FORCEPROP 2 LAST CDS_LIB pure_quanta
J 0
(2500 7025);
PAINT MONO (2500 7025);
DISPLAY INVISIBLE (2500 7025);
FORCEPROP 2 LAST $SEC 1
J 0
(2550 7250);
DISPLAY 0.680851 (2550 7250);
PAINT MONO (2550 7250);
DISPLAY INVISIBLE (2550 7250);
FORCEPROP 2 LAST CDS_SEC 1
J 0
(2550 7250);
DISPLAY 1.021277 (2550 7250);
DISPLAY INVISIBLE (2550 7250);
FORCEADD UNIVERSAL_GND..1
(2450 7600);
FORCEPROP 3 LASTPIN (2450 7650) SIG_NAME GND\g
J 0
(2460 7660);
DISPLAY 0.659574 (2460 7660);
PAINT MONO (2460 7660);
DISPLAY INVISIBLE (2460 7660);
FORCEPROP 1 LAST PATH I8
J 0
(2525 7600);
DISPLAY 0.872340 (2525 7600);
PAINT AQUA (2525 7600);
DISPLAY INVISIBLE (2525 7600);
FORCEPROP 1 LAST HDL_POWER GND
J 1
(2475 7525);
DISPLAY 0.872340 (2475 7525);
PAINT GREEN (2475 7525);
DISPLAY INVISIBLE (2475 7525);
FORCEPROP 2 LAST CDS_LIB logical_power
J 0
(2450 7600);
PAINT MONO (2450 7600);
DISPLAY INVISIBLE (2450 7600);
FORCEADD Q_CAP..1
(2450 7950);
FORCEPROP 1 LAST PART_NUMBER CH6223MEA01
J 0
(2500 7750);
DISPLAY 0.617021 (2500 7750);
PAINT BLUE (2500 7750);
DISPLAY INVISIBLE (2500 7750);
FORCEPROP 1 LAST PACK_TYPE C0805
J 0
(2500 7800);
DISPLAY 0.617021 (2500 7800);
PAINT SKYBLUE (2500 7800);
FORCEPROP 1 LAST MATERIAL X6S
J 0
(2500 7850);
DISPLAY 0.617021 (2500 7850);
PAINT SKYBLUE (2500 7850);
FORCEPROP 1 LAST VALUE 22UF
J 0
(2500 8000);
DISPLAY 0.617021 (2500 8000);
PAINT SKYBLUE (2500 8000);
FORCEPROP 1 LAST VOLTAGE 16V
J 0
(2500 7950);
DISPLAY 0.617021 (2500 7950);
PAINT SKYBLUE (2500 7950);
FORCEPROP 1 LAST TOLERANCE 20%
J 0
(2500 7900);
DISPLAY 0.617021 (2500 7900);
PAINT SKYBLUE (2500 7900);
FORCEPROP 1 LAST LOCATION PC1280
J 0
(2500 8050);
DISPLAY 0.617021 (2500 8050);
PAINT AQUA (2500 8050);
FORCEPROP 1 LASTPIN (2450 8050) $PN 1
J 0
(2460 8030);
DISPLAY 0.617021 (2460 8030);
PAINT MONO (2460 8030);
FORCEPROP 1 LASTPIN (2450 7850) $PN 2
J 0
(2460 7830);
DISPLAY 0.617021 (2460 7830);
PAINT MONO (2460 7830);
FORCEPROP 1 LAST PATH I9
J 0
(2500 8100);
DISPLAY 0.978723 (2500 8100);
PAINT WHITE (2500 8100);
DISPLAY INVISIBLE (2500 8100);
FORCEPROP 2 LAST CDS_LIB pure_quanta
J 0
(2450 7950);
DISPLAY INVISIBLE (2450 7950);
FORCEPROP 2 LAST BOM_COST VR_PCH
J 0
(2500 8100);
DISPLAY 0.680851 (2500 8100);
DISPLAY INVISIBLE (2500 8100);
FORCEPROP 2 LAST $SEC 1
J 0
(2500 8150);
DISPLAY 0.680851 (2500 8150);
PAINT MONO (2500 8150);
DISPLAY INVISIBLE (2500 8150);
FORCEPROP 2 LAST CDS_SEC 1
J 0
(2500 8150);
DISPLAY 1.021277 (2500 8150);
DISPLAY INVISIBLE (2500 8150);
FORCEADD DNS..2
(9475 6125);
PAINT RED (9475 6125);
FORCEPROP 1 LAST COMMENT_BODY TRUE
R 1
J 0
(9550 5900);
DISPLAY 0.872340 (9550 5900);
PAINT GREEN (9550 5900);
DISPLAY INVISIBLE (9550 5900);
FORCEPROP 2 LAST CDS_LIB mstr_misc
J 0
(9475 6125);
DISPLAY INVISIBLE (9475 6125);
FORCEADD DNS..2
(2375 7025);
PAINT RED (2375 7025);
FORCEPROP 1 LAST COMMENT_BODY TRUE
R 1
J 0
(2450 6800);
DISPLAY 0.872340 (2450 6800);
PAINT GREEN (2450 6800);
DISPLAY INVISIBLE (2450 6800);
FORCEPROP 2 LAST CDS_LIB mstr_misc
J 0
(2375 7025);
DISPLAY INVISIBLE (2375 7025);
FORCEADD DNS..2
(1950 7400);
PAINT RED (1950 7400);
FORCEPROP 1 LAST COMMENT_BODY TRUE
R 1
J 0
(2025 7175);
DISPLAY 0.872340 (2025 7175);
PAINT GREEN (2025 7175);
DISPLAY INVISIBLE (2025 7175);
FORCEPROP 2 LAST CDS_LIB mstr_misc
J 0
(1950 7400);
PAINT MONO (1950 7400);
DISPLAY INVISIBLE (1950 7400);
FORCEADD QUANTA_TITLE_BLOCK_C..1
(10250 4425);
FORCEPROP 0 LAST CDS_CON_LAST_MODIFIED Fri Aug 25 14:05:10 2023
J 0
(8365 4440);
DISPLAY INVISIBLE (8365 4440);
FORCEPROP 1 LAST CUSTOM_TXT_CDS <CON_LAST_MODIFIED>
J 0
(8365 4440);
DISPLAY 0.978723 (8365 4440);
FORCEPROP 2 LAST CUSTOM_TXT_CDS <XR_PAGE_TITLE>
J 0
(2360 9675);
DISPLAY 0.638298 (2360 9675);
PAINT PINK (2360 9675);
DISPLAY INVISIBLE (2360 9675);
FORCEPROP 1 LAST CUSTOM_TXT_CDS <NAME_2>
J 0
(7075 4475);
FORCEPROP 1 LAST CUSTOM_TXT_CDS <NAME_1>
J 0
(7075 4600);
FORCEPROP 1 LAST CUSTOM_TXT_CDS <Q_NUMBER>
J 0
(8847 4528);
DISPLAY 1.212766 (8847 4528);
FORCEPROP 1 LAST CUSTOM_TXT_CDS <Q_PROJ>
J 0
(7868 4527);
DISPLAY 1.212766 (7868 4527);
FORCEPROP 1 LAST CUSTOM_TXT_CDS <Q_REV>
J 0
(10066 4528);
DISPLAY 1.212766 (10066 4528);
FORCEPROP 1 LAST CUSTOM_TXT_CDS <CON_PAGE_NUM> OF <CON_TOTAL_PAGES>
J 0
(9804 4443);
DISPLAY 0.978723 (9804 4443);
FORCEPROP 1 LAST Q_TITLE PVNN_MAIN_CPU1
J 0
(950 4475);
DISPLAY 2.446809 (950 4475);
PAINT GREEN (950 4475);
FORCEPROP 1 LAST Q_DEPT 
J 1
(6487 4474);
DISPLAY 1.957447 (6487 4474);
PAINT GREEN (6487 4474);
FORCEPROP 2 LAST CDS_XR_PAGE_TITLE CR-300 : @S9S_MB_2U_LIB.S9S_MB_2U(SCH_1):PAGE300
J 0
(2360 9675);
DISPLAY 0.638298 (2360 9675);
PAINT PINK (2360 9675);
DISPLAY INVISIBLE (2360 9675);
FORCEPROP 2 LAST PAGE_BORDER TRUE
J 0
(2360 9675);
DISPLAY 0.638298 (2360 9675);
PAINT PINK (2360 9675);
DISPLAY INVISIBLE (2360 9675);
FORCEPROP 1 LAST CDS_LMAN_SYM_OUTLINE -9475,6775,100,-125
J 0
(10250 4425);
DISPLAY 0.468085 (10250 4425);
PAINT GREEN (10250 4425);
DISPLAY INVISIBLE (10250 4425);
FORCEPROP 2 LAST CDS_LIB pure_quanta
J 0
(10250 4425);
DISPLAY INVISIBLE (10250 4425);
FORCEPROP 1 LAST COMMENT_BODY TRUE
J 0
(10262 4412);
DISPLAY 0.978723 (10262 4412);
PAINT GREEN (10262 4412);
DISPLAY INVISIBLE (10262 4412);
WIRE 16 -1 (9950 7225)(9950 7350);
WIRE 16 -1 (9950 7225)(9250 7225);
WIRE 16 -1 (9950 7225)(9950 6375);
WIRE 16 -1 (9950 6125)(9950 6175);
WIRE 16 -1 (9500 6125)(9950 6125);
WIRE 16 -1 (6350 8175)(6350 8275);
WIRE 16 -1 (2450 8200)(2450 8350);
WIRE 16 -1 (2900 8200)(2450 8200);
WIRE 16 -1 (2450 8050)(2450 8200);
WIRE 16 -1 (3625 6850)(3625 6825);
WIRE 16 -1 (1200 7450)(1200 7400);
WIRE 16 -1 (9925 5750)(9925 5500);
WIRE 16 -1 (8775 5750)(9925 5750);
WIRE 16 -1 (8875 6800)(8875 6700);
WIRE 16 -1 (8875 6800)(9250 6800);
WIRE 16 -1 (8500 6800)(8875 6800);
WIRE 16 -1 (8875 6800)(8875 6925);
WIRE 16 -1 (7875 7450)(7875 7375);
WIRE 16 -1 (5550 6175)(5550 6425);
WIRE 16 -1 (5400 5675)(5400 5750);
WIRE 16 -1 (4075 5950)(4075 5775);
WIRE 16 -1 (3200 6550)(3200 6400);
WIRE 16 -1 (2450 7725)(2450 7650);
WIRE 16 -1 (2900 7725)(2450 7725);
WIRE 16 -1 (2450 7850)(2450 7725);
WIRE 16 -1 (2400 6850)(2500 6850);
WIRE 16 -1 (2400 6925)(2400 6850);
WIRE 16 -1 (2500 6925)(2500 6850);
WIRE 16 -1 (3625 6000)(3625 5775);
WIRE 16 -1 (5350 6375)(5400 6375);
WIRE 16 -1 (5400 6375)(5400 5750);
WIRE 16 -1 (5400 5750)(6025 5750);
WIRE 16 -1 (6375 5750)(6025 5750);
WIRE 16 -1 (6025 5950)(6025 5750);
WIRE 16 -1 (3625 6200)(3625 6525);
WIRE 16 -1 (3625 6525)(3625 6625);
WIRE 16 -1 (3625 6525)(4425 6525);
FORCEPROP 2 LAST SIG_NAME PVNN_MAIN_CPU1_VCC
J 0
(3865 6535);
DISPLAY 0.617021 (3865 6535);
WIRE 16 -1 (4425 6525)(4425 6775);
WIRE 16 -1 (4425 6775)(4550 6775);
WIRE 16 -1 (6475 7525)(6700 7525);
FORCEPROP 2 LAST SIG_NAME SW_PVNN_MAIN_CPU1_BST_R
J 0
(6540 7535);
DISPLAY 0.617021 (6540 7535);
WIRE 16 -1 (6700 7525)(6700 7475);
WIRE 16 -1 (1200 7400)(1825 7400);
WIRE 16 -1 (2900 7850)(2900 7725);
WIRE 16 -1 (3325 7725)(2900 7725);
WIRE 16 -1 (3325 7850)(3325 7725);
WIRE 16 -1 (5350 6425)(5550 6425);
WIRE 16 -1 (5550 6425)(5550 6625);
WIRE 16 -1 (5350 6625)(5550 6625);
WIRE 16 -1 (4550 7725)(4500 7725);
WIRE 16 -1 (4500 7725)(4500 8200);
WIRE 16 -1 (3325 8050)(3325 8200);
WIRE 16 -1 (4500 8200)(3325 8200);
WIRE 16 -1 (3325 8200)(2900 8200);
WIRE 16 -1 (2900 8050)(2900 8200);
WIRE 16 -1 (7725 6925)(7725 6800);
WIRE 16 -1 (7725 6800)(8125 6800);
WIRE 16 -1 (8125 6925)(8125 6800);
WIRE 16 -1 (8125 6800)(8500 6800);
WIRE 16 -1 (8500 6925)(8500 6800);
WIRE 16 -1 (9250 6800)(9250 6925);
WIRE 16 -1 (8775 6000)(8775 5750);
WIRE 16 -1 (6575 5750)(7075 5750);
WIRE 16 -1 (7075 5750)(8775 5750);
WIRE 16 -1 (7075 5950)(7075 5750);
WIRE 16 -1 (9500 6375)(9950 6375);
WIRE 16 -1 (9250 7125)(9250 7225);
WIRE 16 -1 (8875 7125)(8875 7225);
WIRE 16 -1 (9250 7225)(8875 7225);
WIRE 16 -1 (8500 7125)(8500 7225);
WIRE 16 -1 (8500 7225)(8875 7225);
WIRE 16 -1 (8125 7125)(8125 7225);
WIRE 16 -1 (8125 7225)(8500 7225);
WIRE 16 -1 (7400 7225)(7725 7225);
WIRE 16 -1 (7725 7225)(8125 7225);
WIRE 16 -1 (7725 7125)(7725 7225);
WIRE 16 2175 (7800 9725)(9775 9725);
WIRE 16 2175 (9775 10750)(9775 9725);
WIRE 16 2175 (7800 10750)(7800 9725);
WIRE 16 2175 (7800 10750)(9775 10750);
WIRE 16 -1 (9025 6125)(9300 6125);
WIRE 16 -1 (9025 6375)(9025 6125);
WIRE 16 -1 (9300 6375)(9025 6375);
WIRE 16 -1 (8775 6375)(8775 6200);
WIRE 16 -1 (9025 6375)(8775 6375);
WIRE 16 -1 (8525 6375)(8175 6375);
WIRE 16 -1 (8775 6375)(8525 6375);
FORCEPROP 2 LAST SIG_NAME PVNN_MAIN_CPU1_FB_RC
J 0
(8540 6385);
DISPLAY 0.617021 (8540 6385);
WIRE 16 -1 (8525 6025)(8525 6375);
WIRE 16 -1 (8175 6025)(8525 6025);
WIRE 16 -1 (7975 6025)(7775 6025);
WIRE 16 -1 (7775 6025)(7775 6375);
WIRE 16 -1 (7975 6375)(7775 6375);
WIRE 16 -1 (7075 6150)(7075 6375);
WIRE 16 -1 (7775 6375)(7075 6375);
WIRE 16 -1 (6350 6775)(5350 6775);
WIRE 16 -1 (7075 6375)(6350 6375);
FORCEPROP 2 LAST SIG_NAME PVNN_MAIN_CPU1_FB
J 0
(5615 6785);
DISPLAY 0.617021 (5615 6785);
WIRE 16 -1 (6350 6375)(6350 6775);
WIRE 16 -1 (7875 7725)(7475 7725);
WIRE 16 -1 (7875 7650)(7875 7725);
WIRE 16 -1 (8725 7725)(7875 7725);
FORCEPROP 2 LAST SIG_NAME PWRGD_PVNN_MAIN_CPU1
J 0
(7990 7735);
DISPLAY 0.617021 (7990 7735);
WIRE 16 -1 (5350 7275)(5500 7275);
WIRE 16 -1 (5350 7225)(5500 7225);
WIRE 16 -1 (5500 7275)(5500 7225);
WIRE 16 -1 (5500 7225)(6700 7225);
FORCEPROP 2 LAST SIG_NAME SW_PVNN_MAIN_CPU1_SW
J 0
(5540 7235);
DISPLAY 0.617021 (5540 7235);
WIRE 16 -1 (7200 7225)(6700 7225);
WIRE 16 -1 (6700 7275)(6700 7225);
WIRE 16 -1 (5350 7725)(6350 7725);
FORCEPROP 2 LAST SIG_NAME PWRGD_PVNN_MAIN_CPU1_R
J 0
(5540 7735);
DISPLAY 0.617021 (5540 7735);
WIRE 16 -1 (7275 7725)(6350 7725);
WIRE 16 -1 (6350 7975)(6350 7725);
WIRE 16 -1 (6275 7525)(5350 7525);
FORCEPROP 2 LAST SIG_NAME SW_PVNN_MAIN_CPU1_BST
J 0
(5540 7535);
DISPLAY 0.617021 (5540 7535);
WIRE 16 -1 (5350 6525)(6025 6525);
FORCEPROP 2 LAST SIG_NAME PVNN_MAIN_CPU1_REF
J 0
(5615 6535);
DISPLAY 0.617021 (5615 6535);
WIRE 16 -1 (6025 6525)(6025 6150);
WIRE 16 -1 (4075 6150)(4075 6425);
FORCEPROP 2 LAST SIG_NAME PVNN_MAIN_CPU1_CS
J 0
(3865 6435);
DISPLAY 0.617021 (3865 6435);
WIRE 16 -1 (4075 6425)(4550 6425);
WIRE 16 -1 (3200 6750)(3200 7025);
WIRE 16 -1 (3200 7025)(4550 7025);
FORCEPROP 2 LAST SIG_NAME PVNN_MAIN_CPU1_MODE
J 0
(3865 7035);
DISPLAY 0.617021 (3865 7035);
WIRE 16 -1 (2400 7125)(2400 7175);
WIRE 16 -1 (2500 7125)(2500 7175);
WIRE 16 -1 (2400 7175)(2500 7175);
WIRE 16 -1 (2625 7400)(2025 7400);
WIRE 16 -1 (1400 7225)(2500 7225);
WIRE 16 -1 (2500 7175)(2500 7225);
WIRE 16 -1 (2500 7225)(2625 7225);
WIRE 16 -1 (2625 7225)(2625 7400);
WIRE 16 -1 (4550 7225)(2625 7225);
WIRE 16 2175 (1275 5525)(2375 5525);
WIRE 16 2175 (2375 5525)(2375 5050);
WIRE 16 2175 (1275 5525)(1275 5050);
WIRE 16 2175 (1275 5050)(2375 5050);
DOT 1 (9950 7225);
DOT 1 (9250 7225);
DOT 1 (8875 7225);
DOT 1 (9025 6375);
DOT 1 (8875 6800);
DOT 1 (8775 6375);
DOT 1 (8500 7225);
DOT 1 (7875 7725);
DOT 1 (8125 7225);
DOT 1 (8500 6800);
DOT 1 (8525 6375);
DOT 1 (8125 6800);
DOT 1 (7775 6375);
DOT 1 (8775 5750);
DOT 1 (3325 8200);
DOT 1 (2900 8200);
DOT 1 (2450 8200);
DOT 1 (7725 7225);
DOT 1 (7075 6375);
DOT 1 (6350 7725);
DOT 1 (6700 7225);
DOT 1 (7075 5750);
DOT 1 (6025 5750);
DOT 1 (5500 7225);
DOT 1 (5550 6425);
DOT 1 (5400 5750);
DOT 1 (2900 7725);
DOT 1 (3625 6525);
DOT 1 (2625 7225);
DOT 1 (2450 7725);
DOT 1 (2500 7225);
DOT 1 (2500 7175);
FORCENOTE
RIPPLE=+/-7MV
(7825 10375) 0;
DISPLAY LEFT (7825 10375);
DISPLAY 1.170213 (7825 10375);
PAINT RED (7825 10375);
FORCENOTE
PVNN_MAIN_CPU1
(4075 9525) 0;
DISPLAY LEFT (4075 9525);
DISPLAY 3.148936 (4075 9525);
PAINT YELLOW (4075 9525);
FORCENOTE
20220808 UPDATE PDG REV 1.6
(7800 9600) 0;
DISPLAY LEFT (7800 9600);
DISPLAY 1.595745 (7800 9600);
FORCENOTE
CURRENT STEP=0.52A
(7826 9986) 0;
DISPLAY LEFT (7826 9986);
DISPLAY 1.170213 (7826 9986);
PAINT RED (7826 9986);
FORCENOTE
PVNN_MAIN_CPU1 SPECIFICATION
(7825 10665) 0;
DISPLAY LEFT (7825 10665);
DISPLAY 1.468085 (7825 10665);
PAINT WHITE (7825 10665);
FORCENOTE
TOTAL TOL=1.03VMAX/0.97VMIN 
(7825 10300) 0;
DISPLAY LEFT (7825 10300);
DISPLAY 1.276596 (7825 10300);
PAINT RED (7825 10300);
FORCENOTE
DC TOLERANCE=+/-0.7%
(7825 10450) 0;
DISPLAY LEFT (7825 10450);
DISPLAY 1.276596 (7825 10450);
PAINT WHITE (7825 10450);
FORCENOTE
TDC=0.52A
(7825 10225) 0;
DISPLAY LEFT (7825 10225);
DISPLAY 1.170213 (7825 10225);
PAINT RED (7825 10225);
FORCENOTE
VOUT=1V
(7825 10550) 0;
DISPLAY LEFT (7825 10550);
DISPLAY 1.170213 (7825 10550);
PAINT WHITE (7825 10550);
FORCENOTE
MAX CURRENT=0.52A
(7826 10136) 0;
DISPLAY LEFT (7826 10136);
DISPLAY 1.170213 (7826 10136);
PAINT RED (7826 10136);
FORCENOTE
OCP(IMAX*130%)=1A
(7826 10061) 0;
DISPLAY LEFT (7826 10061);
DISPLAY 1.170213 (7826 10061);
PAINT WHITE (7826 10061);
FORCENOTE
SLEW RATE=0.4A/US
(7826 9911) 0;
DISPLAY LEFT (7826 9911);
DISPLAY 1.170213 (7826 9911);
PAINT RED (7826 9911);
FORCENOTE
PDG REV 1.6
(7825 9750) 0;
DISPLAY LEFT (7825 9750);
DISPLAY 1.170213 (7825 9750);
PAINT RED (7825 9750);
FORCENOTE
WORK FREQUENCY=600KHZ
(7826 9841) 0;
DISPLAY LEFT (7826 9841);
DISPLAY 1.170213 (7826 9841);
PAINT WHITE (7826 9841);
FORCENOTE
UPDATE 20220531 ADD LOCAL SENSE
(8425 6525) 0;
DISPLAY LEFT (8425 6525);
DISPLAY 1.021277 (8425 6525);
FORCENOTE
PLACE AT CHIPSET SIDE
(9200 5825) 0;
DISPLAY LEFT (9200 5825);
DISPLAY 1.021277 (9200 5825);
FORCENOTE
REMOTE SENSE
(9200 5900) 0;
DISPLAY LEFT (9200 5900);
DISPLAY 1.021277 (9200 5900);
FORCENOTE
3RD 680PF
(8250 5250) 0;
DISPLAY LEFT (8250 5250);
DISPLAY 1.276596 (8250 5250);
PAINT PINK (8250 5250);
FORCENOTE
2ND 470PF
(8250 5350) 0;
DISPLAY LEFT (8250 5350);
DISPLAY 1.276596 (8250 5350);
PAINT PINK (8250 5350);
FORCENOTE
PC238 MAIN 680PF
(7825 5450) 0;
DISPLAY LEFT (7825 5450);
DISPLAY 1.276596 (7825 5450);
PAINT PINK (7825 5450);
FORCENOTE
20220808 ADD CHANGE LIST
(7125 5550) 0;
DISPLAY LEFT (7125 5550);
DISPLAY 1.595745 (7125 5550);
PAINT PINK (7125 5550);
FORCENOTE
DCR=40M OHM
(7025 6950) 0;
DISPLAY LEFT (7025 6950);
DISPLAY 0.808511 (7025 6950);
FORCENOTE
PCMC063T-4R7MN
(7025 7100) 0;
DISPLAY LEFT (7025 7100);
DISPLAY 0.808511 (7025 7100);
FORCENOTE
ISAT=9A@100C
(7025 7000) 0;
DISPLAY LEFT (7025 7000);
DISPLAY 0.808511 (7025 7000);
FORCENOTE
6.5*6.9*3.0
(7025 7050) 0;
DISPLAY LEFT (7025 7050);
DISPLAY 0.808511 (7025 7050);
FORCENOTE
IC TABLE
(1350 5425) 0;
DISPLAY LEFT (1350 5425);
DISPLAY 1.170213 (1350 5425);
PAINT WHITE (1350 5425);
FORCENOTE
1ST AL053317005
(1350 5325) 0;
DISPLAY LEFT (1350 5325);
DISPLAY 1.170213 (1350 5325);
PAINT WHITE (1350 5325);
FORCENOTE
20220804 CHANGE IC TABLE
(1325 4875) 0;
DISPLAY LEFT (1325 4875);
DISPLAY 1.595745 (1325 4875);
PAINT PINK (1325 4875);
FORCENOTE
2ND AL54L061000
(1350 5225) 0;
DISPLAY LEFT (1350 5225);
DISPLAY 1.170213 (1350 5225);
PAINT WHITE (1350 5225);
FORCENOTE
3RD AL008626000
(1350 5125) 0;
DISPLAY LEFT (1350 5125);
DISPLAY 1.170213 (1350 5125);
PAINT WHITE (1350 5125);
QUIT
